FILE_TYPE = MACRO_DRAWING;
SET COLOR_WIRE YELLOW;
SET COLOR_PROP ORANGE;
SET COLOR_DOT WHITE;
SET COLOR_ARC YELLOW;
SET COLOR_BODY GREEN;
SET COLOR_NOTE PURPLE;
SET PROP_DISPLAY VALUE;
SET PAGE_NUMBER P177;
FORCEADD Q_RES..1
(4225 -750);
FORCEPROP 1 LAST PART_NUMBER CS03322FB03
J 0
(4125 -675);
DISPLAY 0.510638 (4125 -675);
DISPLAY INVISIBLE (4125 -675);
FORCEPROP 1 LAST VALUE 33.2
J 2
(4425 -750);
DISPLAY 0.510638 (4425 -750);
FORCEPROP 1 LAST PACK_TYPE 0402LF
J 0
(4125 -625);
DISPLAY 0.510638 (4125 -625);
FORCEPROP 1 LAST MATERIAL CHIP
J 0
(4525 -750);
DISPLAY 0.510638 (4525 -750);
FORCEPROP 1 LAST WATTAGE 1/16W
J 2
(4425 -625);
DISPLAY 0.510638 (4425 -625);
FORCEPROP 1 LAST TOLERANCE 1%
J 0
(4450 -750);
DISPLAY 0.510638 (4450 -750);
FORCEPROP 1 LAST $LOCATION R501
J 0
(3950 -750);
DISPLAY 0.638298 (3950 -750);
FORCEPROP 1 LASTPIN (4125 -750) $PN 1
J 0
(4137 -738);
DISPLAY 0.787234 (4137 -738);
FORCEPROP 1 LASTPIN (4325 -750) $PN 2
J 0
(4287 -738);
DISPLAY 0.787234 (4287 -738);
FORCEPROP 1 LAST PATH I100
J 0
(4175 -600);
DISPLAY 0.978723 (4175 -600);
PAINT WHITE (4175 -600);
DISPLAY INVISIBLE (4175 -600);
FORCEPROP 2 LAST CDS_LIB pure_quanta
J 0
(4225 -750);
PAINT MONO (4225 -750);
DISPLAY INVISIBLE (4225 -750);
FORCEPROP 2 LAST CDS_LOCATION R501
J 0
(4175 -550);
DISPLAY 1.021277 (4175 -550);
DISPLAY INVISIBLE (4175 -550);
FORCEPROP 2 LAST $SEC 1
J 0
(4175 -550);
DISPLAY 0.680851 (4175 -550);
PAINT MONO (4175 -550);
DISPLAY INVISIBLE (4175 -550);
FORCEPROP 2 LAST CDS_SEC 1
J 0
(4175 -550);
DISPLAY 1.021277 (4175 -550);
DISPLAY INVISIBLE (4175 -550);
FORCEADD Q_RES..1
(4225 -900);
FORCEPROP 1 LAST PART_NUMBER CS03322FB03
J 0
(4125 -800);
DISPLAY 0.510638 (4125 -800);
DISPLAY INVISIBLE (4125 -800);
FORCEPROP 1 LAST MATERIAL CHIP
J 0
(4525 -900);
DISPLAY 0.510638 (4525 -900);
FORCEPROP 1 LAST TOLERANCE 1%
J 0
(4450 -900);
DISPLAY 0.510638 (4450 -900);
FORCEPROP 1 LAST VALUE 33.2
J 2
(4425 -900);
DISPLAY 0.510638 (4425 -900);
FORCEPROP 1 LAST $LOCATION R1395
J 0
(3950 -900);
DISPLAY 0.638298 (3950 -900);
FORCEPROP 1 LASTPIN (4125 -900) $PN 1
J 0
(4137 -888);
DISPLAY 0.787234 (4137 -888);
FORCEPROP 1 LASTPIN (4325 -900) $PN 2
J 0
(4287 -888);
DISPLAY 0.787234 (4287 -888);
FORCEPROP 1 LAST PATH I102
J 0
(4175 -750);
DISPLAY 0.978723 (4175 -750);
PAINT WHITE (4175 -750);
DISPLAY INVISIBLE (4175 -750);
FORCEPROP 2 LAST CDS_LIB pure_quanta
J 0
(4225 -900);
PAINT MONO (4225 -900);
DISPLAY INVISIBLE (4225 -900);
FORCEPROP 1 LAST PACK_TYPE 0402LF
J 0
(4125 -750);
DISPLAY 0.510638 (4125 -750);
DISPLAY INVISIBLE (4125 -750);
FORCEPROP 1 LAST WATTAGE 1/16W
J 2
(4425 -750);
DISPLAY 0.510638 (4425 -750);
DISPLAY INVISIBLE (4425 -750);
FORCEPROP 2 LAST CDS_LOCATION R1395
J 0
(4175 -700);
DISPLAY 1.021277 (4175 -700);
DISPLAY INVISIBLE (4175 -700);
FORCEPROP 2 LAST $SEC 1
J 0
(4175 -700);
DISPLAY 0.680851 (4175 -700);
PAINT MONO (4175 -700);
DISPLAY INVISIBLE (4175 -700);
FORCEPROP 2 LAST CDS_SEC 1
J 0
(4175 -700);
DISPLAY 1.021277 (4175 -700);
DISPLAY INVISIBLE (4175 -700);
FORCEADD Q_RES..1
(4200 -1475);
FORCEPROP 1 LAST PART_NUMBER CS03322FB03
J 0
(4100 -1400);
DISPLAY 0.510638 (4100 -1400);
DISPLAY INVISIBLE (4100 -1400);
FORCEPROP 1 LAST VALUE 33.2
J 2
(4400 -1475);
DISPLAY 0.510638 (4400 -1475);
FORCEPROP 1 LAST MATERIAL CHIP
J 0
(4500 -1475);
DISPLAY 0.510638 (4500 -1475);
FORCEPROP 1 LAST TOLERANCE 1%
J 0
(4425 -1475);
DISPLAY 0.510638 (4425 -1475);
FORCEPROP 1 LAST $LOCATION R499
J 0
(3975 -1475);
DISPLAY 0.638298 (3975 -1475);
FORCEPROP 1 LASTPIN (4100 -1475) $PN 1
J 0
(4112 -1463);
DISPLAY 0.787234 (4112 -1463);
FORCEPROP 1 LASTPIN (4300 -1475) $PN 2
J 0
(4262 -1463);
DISPLAY 0.787234 (4262 -1463);
FORCEPROP 1 LAST PATH I106
J 0
(4150 -1325);
DISPLAY 0.978723 (4150 -1325);
PAINT WHITE (4150 -1325);
DISPLAY INVISIBLE (4150 -1325);
FORCEPROP 2 LAST CDS_LIB pure_quanta
J 0
(4200 -1475);
PAINT MONO (4200 -1475);
DISPLAY INVISIBLE (4200 -1475);
FORCEPROP 1 LAST PACK_TYPE 0402LF
J 0
(4100 -1350);
DISPLAY 0.510638 (4100 -1350);
DISPLAY INVISIBLE (4100 -1350);
FORCEPROP 1 LAST WATTAGE 1/16W
J 2
(4400 -1350);
DISPLAY 0.510638 (4400 -1350);
DISPLAY INVISIBLE (4400 -1350);
FORCEPROP 2 LAST CDS_LOCATION R499
J 0
(4150 -1275);
DISPLAY 1.021277 (4150 -1275);
DISPLAY INVISIBLE (4150 -1275);
FORCEPROP 2 LAST $SEC 1
J 0
(4150 -1275);
DISPLAY 0.680851 (4150 -1275);
PAINT MONO (4150 -1275);
DISPLAY INVISIBLE (4150 -1275);
FORCEPROP 2 LAST CDS_SEC 1
J 0
(4150 -1275);
DISPLAY 1.021277 (4150 -1275);
DISPLAY INVISIBLE (4150 -1275);
FORCEADD OFFPAGE..1
(2525 -750);
FORCEPROP 2 LAST $XR0 185 
J 0
(2273 -750);
DISPLAY 0.638298 (2273 -750);
PAINT MONO (2273 -750);
FORCEPROP 2 LAST PATH I108
J 0
(2250 -700);
DISPLAY 1.021277 (2250 -700);
DISPLAY INVISIBLE (2250 -700);
FORCEPROP 1 LAST COMMENT_BODY TRUE
J 0
(2650 -850);
DISPLAY 0.872340 (2650 -850);
PAINT GREEN (2650 -850);
DISPLAY INVISIBLE (2650 -850);
FORCEPROP 1 LAST OFFPAGE TRUE
J 0
(2850 -875);
DISPLAY 0.872340 (2850 -875);
PAINT GREEN (2850 -875);
DISPLAY INVISIBLE (2850 -875);
FORCEPROP 2 LAST CDS_LIB standard
J 0
(2525 -750);
PAINT MONO (2525 -750);
DISPLAY INVISIBLE (2525 -750);
FORCEADD OFFPAGE..1
(2525 -900);
FORCEPROP 2 LAST $XR0 185 
J 0
(2273 -900);
DISPLAY 0.638298 (2273 -900);
PAINT MONO (2273 -900);
FORCEPROP 2 LAST PATH I110
J 0
(2250 -850);
DISPLAY 1.021277 (2250 -850);
DISPLAY INVISIBLE (2250 -850);
FORCEPROP 1 LAST COMMENT_BODY TRUE
J 0
(2650 -1000);
DISPLAY 0.872340 (2650 -1000);
PAINT GREEN (2650 -1000);
DISPLAY INVISIBLE (2650 -1000);
FORCEPROP 1 LAST OFFPAGE TRUE
J 0
(2850 -1025);
DISPLAY 0.872340 (2850 -1025);
PAINT GREEN (2850 -1025);
DISPLAY INVISIBLE (2850 -1025);
FORCEPROP 2 LAST CDS_LIB standard
J 0
(2525 -900);
PAINT MONO (2525 -900);
DISPLAY INVISIBLE (2525 -900);
FORCEADD OFFPAGE..1
(2525 -1175);
FORCEPROP 2 LAST $XR0 185 
J 0
(2273 -1175);
DISPLAY 0.638298 (2273 -1175);
PAINT MONO (2273 -1175);
FORCEPROP 2 LAST PATH I111
J 0
(2250 -1125);
DISPLAY 1.021277 (2250 -1125);
DISPLAY INVISIBLE (2250 -1125);
FORCEPROP 1 LAST COMMENT_BODY TRUE
J 0
(2650 -1275);
DISPLAY 0.872340 (2650 -1275);
PAINT GREEN (2650 -1275);
DISPLAY INVISIBLE (2650 -1275);
FORCEPROP 1 LAST OFFPAGE TRUE
J 0
(2850 -1300);
DISPLAY 0.872340 (2850 -1300);
PAINT GREEN (2850 -1300);
DISPLAY INVISIBLE (2850 -1300);
FORCEPROP 2 LAST CDS_LIB standard
J 0
(2525 -1175);
PAINT MONO (2525 -1175);
DISPLAY INVISIBLE (2525 -1175);
FORCEADD OFFPAGE..1
(2525 -1250);
FORCEPROP 2 LAST $XR0 185 
J 0
(2273 -1250);
DISPLAY 0.638298 (2273 -1250);
PAINT MONO (2273 -1250);
FORCEPROP 2 LAST PATH I112
J 0
(2250 -1200);
DISPLAY 1.021277 (2250 -1200);
DISPLAY INVISIBLE (2250 -1200);
FORCEPROP 1 LAST COMMENT_BODY TRUE
J 0
(2650 -1350);
DISPLAY 0.872340 (2650 -1350);
PAINT GREEN (2650 -1350);
DISPLAY INVISIBLE (2650 -1350);
FORCEPROP 1 LAST OFFPAGE TRUE
J 0
(2850 -1375);
DISPLAY 0.872340 (2850 -1375);
PAINT GREEN (2850 -1375);
DISPLAY INVISIBLE (2850 -1375);
FORCEPROP 2 LAST CDS_LIB standard
J 0
(2525 -1250);
PAINT MONO (2525 -1250);
DISPLAY INVISIBLE (2525 -1250);
FORCEADD OFFPAGE..1
(2525 -1400);
FORCEPROP 2 LAST $XR0 185 
J 0
(2273 -1400);
DISPLAY 0.638298 (2273 -1400);
PAINT MONO (2273 -1400);
FORCEPROP 2 LAST PATH I113
J 0
(2250 -1350);
DISPLAY 1.021277 (2250 -1350);
DISPLAY INVISIBLE (2250 -1350);
FORCEPROP 1 LAST COMMENT_BODY TRUE
J 0
(2650 -1500);
DISPLAY 0.872340 (2650 -1500);
PAINT GREEN (2650 -1500);
DISPLAY INVISIBLE (2650 -1500);
FORCEPROP 1 LAST OFFPAGE TRUE
J 0
(2850 -1525);
DISPLAY 0.872340 (2850 -1525);
PAINT GREEN (2850 -1525);
DISPLAY INVISIBLE (2850 -1525);
FORCEPROP 2 LAST CDS_LIB standard
J 0
(2525 -1400);
PAINT MONO (2525 -1400);
DISPLAY INVISIBLE (2525 -1400);
FORCEADD OFFPAGE..1
(2525 -1325);
FORCEPROP 2 LAST $XR0 185 
J 0
(2273 -1325);
DISPLAY 0.638298 (2273 -1325);
PAINT MONO (2273 -1325);
FORCEPROP 2 LAST PATH I114
J 0
(2250 -1275);
DISPLAY 1.021277 (2250 -1275);
DISPLAY INVISIBLE (2250 -1275);
FORCEPROP 1 LAST COMMENT_BODY TRUE
J 0
(2650 -1425);
DISPLAY 0.872340 (2650 -1425);
PAINT GREEN (2650 -1425);
DISPLAY INVISIBLE (2650 -1425);
FORCEPROP 1 LAST OFFPAGE TRUE
J 0
(2850 -1450);
DISPLAY 0.872340 (2850 -1450);
PAINT GREEN (2850 -1450);
DISPLAY INVISIBLE (2850 -1450);
FORCEPROP 2 LAST CDS_LIB standard
J 0
(2525 -1325);
PAINT MONO (2525 -1325);
DISPLAY INVISIBLE (2525 -1325);
FORCEADD OFFPAGE..1
(2525 -1475);
FORCEPROP 2 LAST $XR0 185 
J 0
(2273 -1475);
DISPLAY 0.638298 (2273 -1475);
PAINT MONO (2273 -1475);
FORCEPROP 2 LAST PATH I115
J 0
(2250 -1425);
DISPLAY 1.021277 (2250 -1425);
DISPLAY INVISIBLE (2250 -1425);
FORCEPROP 1 LAST COMMENT_BODY TRUE
J 0
(2650 -1575);
DISPLAY 0.872340 (2650 -1575);
PAINT GREEN (2650 -1575);
DISPLAY INVISIBLE (2650 -1575);
FORCEPROP 1 LAST OFFPAGE TRUE
J 0
(2850 -1600);
DISPLAY 0.872340 (2850 -1600);
PAINT GREEN (2850 -1600);
DISPLAY INVISIBLE (2850 -1600);
FORCEPROP 2 LAST CDS_LIB standard
J 0
(2525 -1475);
PAINT MONO (2525 -1475);
DISPLAY INVISIBLE (2525 -1475);
FORCEADD UNIVERSAL_POWER..1
R 2
(4075 775);
FORCEPROP 1 LAST HDL_POWER P3V_BAT_R
J 1
(4075 825);
DISPLAY 1.148936 (4075 825);
PAINT GREEN (4075 825);
FORCEPROP 1 LAST PATH I116
J 2
(4025 800);
DISPLAY 0.872340 (4025 800);
PAINT AQUA (4025 800);
DISPLAY INVISIBLE (4025 800);
FORCEPROP 2 LAST CDS_LIB logical_power
J 0
(4075 775);
DISPLAY INVISIBLE (4075 775);
FORCEADD OFFPAGE..2
(4250 3050);
FORCEPROP 2 LAST $XR1 205 
J 0
(4559 3050);
DISPLAY 0.638298 (4559 3050);
PAINT MONO (4559 3050);
FORCEPROP 2 LAST $XR0 204 
J 0
(4439 3050);
DISPLAY 0.638298 (4439 3050);
PAINT MONO (4439 3050);
FORCEPROP 2 LAST PATH I117
J 0
(4600 3100);
DISPLAY 1.021277 (4600 3100);
DISPLAY INVISIBLE (4600 3100);
FORCEPROP 1 LAST COMMENT_BODY TRUE
J 0
(4205 2955);
DISPLAY 1.170213 (4205 2955);
PAINT GREEN (4205 2955);
DISPLAY INVISIBLE (4205 2955);
FORCEPROP 1 LAST OFFPAGE TRUE
J 0
(4575 2925);
DISPLAY 1.170213 (4575 2925);
PAINT GREEN (4575 2925);
DISPLAY INVISIBLE (4575 2925);
FORCEPROP 2 LAST CDS_LIB standard
J 0
(4250 3050);
DISPLAY INVISIBLE (4250 3050);
FORCEADD Q_RES..1
(4200 -1175);
FORCEPROP 1 LAST PART_NUMBER CS00002JB13
J 0
(4150 -1125);
DISPLAY 0.404255 (4150 -1125);
DISPLAY INVISIBLE (4150 -1125);
FORCEPROP 1 LAST WATTAGE 1/16W
J 2
(4325 -1150);
DISPLAY 0.404255 (4325 -1150);
FORCEPROP 1 LAST PACK_TYPE 0402LF
J 0
(4100 -1150);
DISPLAY 0.404255 (4100 -1150);
FORCEPROP 1 LAST MATERIAL CHIP
J 0
(4450 -1175);
DISPLAY 0.510638 (4450 -1175);
FORCEPROP 1 LAST VALUE 0
J 2
(4350 -1175);
DISPLAY 0.510638 (4350 -1175);
FORCEPROP 1 LAST TOLERANCE 5%
J 0
(4375 -1175);
DISPLAY 0.510638 (4375 -1175);
FORCEPROP 1 LAST LOCATION R915
J 0
(3975 -1175);
DISPLAY 0.638298 (3975 -1175);
FORCEPROP 1 LASTPIN (4100 -1175) $PN 1
J 0
(4112 -1163);
DISPLAY 0.787234 (4112 -1163);
PAINT MONO (4112 -1163);
FORCEPROP 1 LASTPIN (4300 -1175) $PN 2
J 0
(4262 -1163);
DISPLAY 0.787234 (4262 -1163);
PAINT MONO (4262 -1163);
FORCEPROP 1 LAST PATH I118
J 0
(4150 -1025);
DISPLAY 0.978723 (4150 -1025);
PAINT WHITE (4150 -1025);
DISPLAY INVISIBLE (4150 -1025);
FORCEPROP 2 LAST CDS_LIB pure_quanta
J 0
(4200 -1175);
DISPLAY INVISIBLE (4200 -1175);
FORCEPROP 0 LAST $SEC 1
J 0
(4325 -1125);
DISPLAY 0.680851 (4325 -1125);
PAINT MONO (4325 -1125);
DISPLAY INVISIBLE (4325 -1125);
FORCEPROP 0 LAST CDS_SEC 1
J 0
(4325 -1125);
DISPLAY 1.021277 (4325 -1125);
DISPLAY INVISIBLE (4325 -1125);
FORCEADD Q_RES..1
(4200 -1250);
FORCEPROP 1 LAST PART_NUMBER CS00002JB13
J 0
(4150 -1200);
DISPLAY 0.404255 (4150 -1200);
DISPLAY INVISIBLE (4150 -1200);
FORCEPROP 1 LAST WATTAGE 1/16W
J 2
(4325 -1225);
DISPLAY 0.404255 (4325 -1225);
FORCEPROP 1 LAST PACK_TYPE 0402LF
J 0
(4100 -1225);
DISPLAY 0.404255 (4100 -1225);
FORCEPROP 1 LAST VALUE 0
J 2
(4350 -1250);
DISPLAY 0.510638 (4350 -1250);
FORCEPROP 1 LAST TOLERANCE 5%
J 0
(4375 -1250);
DISPLAY 0.510638 (4375 -1250);
FORCEPROP 1 LAST MATERIAL CHIP
J 0
(4450 -1250);
DISPLAY 0.510638 (4450 -1250);
FORCEPROP 1 LAST LOCATION R916
J 0
(3975 -1250);
DISPLAY 0.638298 (3975 -1250);
FORCEPROP 1 LASTPIN (4100 -1250) $PN 1
J 0
(4112 -1238);
DISPLAY 0.787234 (4112 -1238);
PAINT MONO (4112 -1238);
FORCEPROP 1 LASTPIN (4300 -1250) $PN 2
J 0
(4262 -1238);
DISPLAY 0.787234 (4262 -1238);
PAINT MONO (4262 -1238);
FORCEPROP 1 LAST PATH I119
J 0
(4150 -1100);
DISPLAY 0.978723 (4150 -1100);
PAINT WHITE (4150 -1100);
DISPLAY INVISIBLE (4150 -1100);
FORCEPROP 2 LAST CDS_LIB pure_quanta
J 0
(4200 -1250);
DISPLAY INVISIBLE (4200 -1250);
FORCEPROP 0 LAST $SEC 1
J 0
(4325 -1200);
DISPLAY 0.680851 (4325 -1200);
PAINT MONO (4325 -1200);
DISPLAY INVISIBLE (4325 -1200);
FORCEPROP 0 LAST CDS_SEC 1
J 0
(4325 -1200);
DISPLAY 1.021277 (4325 -1200);
DISPLAY INVISIBLE (4325 -1200);
FORCEADD OFFPAGE..2
(4250 2450);
FORCEPROP 2 LAST $XR0 185 
J 0
(4439 2450);
DISPLAY 0.638298 (4439 2450);
PAINT MONO (4439 2450);
FORCEPROP 2 LAST PATH I12
J 0
(4425 2525);
DISPLAY 1.021277 (4425 2525);
DISPLAY INVISIBLE (4425 2525);
FORCEPROP 1 LAST COMMENT_BODY TRUE
J 0
(4205 2355);
DISPLAY 1.170213 (4205 2355);
PAINT GREEN (4205 2355);
DISPLAY INVISIBLE (4205 2355);
FORCEPROP 1 LAST OFFPAGE TRUE
J 0
(4575 2325);
DISPLAY 1.170213 (4575 2325);
PAINT GREEN (4575 2325);
DISPLAY INVISIBLE (4575 2325);
FORCEPROP 2 LAST CDS_LIB standard
J 0
(4250 2450);
PAINT MONO (4250 2450);
DISPLAY INVISIBLE (4250 2450);
FORCEADD Q_RES..1
(4200 -1325);
FORCEPROP 1 LAST PART_NUMBER CS00002JB13
J 0
(4150 -1275);
DISPLAY 0.404255 (4150 -1275);
DISPLAY INVISIBLE (4150 -1275);
FORCEPROP 1 LAST MATERIAL CHIP
J 0
(4450 -1325);
DISPLAY 0.510638 (4450 -1325);
FORCEPROP 1 LAST TOLERANCE 5%
J 0
(4375 -1325);
DISPLAY 0.510638 (4375 -1325);
FORCEPROP 1 LAST VALUE 0
J 2
(4350 -1325);
DISPLAY 0.510638 (4350 -1325);
FORCEPROP 1 LAST WATTAGE 1/16W
J 2
(4325 -1300);
DISPLAY 0.404255 (4325 -1300);
FORCEPROP 1 LAST PACK_TYPE 0402LF
J 0
(4100 -1300);
DISPLAY 0.404255 (4100 -1300);
FORCEPROP 1 LAST LOCATION R918
J 0
(3975 -1325);
DISPLAY 0.638298 (3975 -1325);
FORCEPROP 1 LASTPIN (4100 -1325) $PN 1
J 0
(4112 -1313);
DISPLAY 0.787234 (4112 -1313);
PAINT MONO (4112 -1313);
FORCEPROP 1 LASTPIN (4300 -1325) $PN 2
J 0
(4262 -1313);
DISPLAY 0.787234 (4262 -1313);
PAINT MONO (4262 -1313);
FORCEPROP 1 LAST PATH I120
J 0
(4150 -1175);
DISPLAY 0.978723 (4150 -1175);
PAINT WHITE (4150 -1175);
DISPLAY INVISIBLE (4150 -1175);
FORCEPROP 2 LAST CDS_LIB pure_quanta
J 0
(4200 -1325);
DISPLAY INVISIBLE (4200 -1325);
FORCEPROP 0 LAST $SEC 1
J 0
(4325 -1275);
DISPLAY 0.680851 (4325 -1275);
PAINT MONO (4325 -1275);
DISPLAY INVISIBLE (4325 -1275);
FORCEPROP 0 LAST CDS_SEC 1
J 0
(4325 -1275);
DISPLAY 1.021277 (4325 -1275);
DISPLAY INVISIBLE (4325 -1275);
FORCEADD Q_RES..1
(4200 -1400);
FORCEPROP 1 LAST PART_NUMBER CS00002JB13
J 0
(4150 -1350);
DISPLAY 0.404255 (4150 -1350);
DISPLAY INVISIBLE (4150 -1350);
FORCEPROP 1 LAST PACK_TYPE 0402LF
J 0
(4100 -1375);
DISPLAY 0.404255 (4100 -1375);
FORCEPROP 1 LAST WATTAGE 1/16W
J 2
(4325 -1375);
DISPLAY 0.404255 (4325 -1375);
FORCEPROP 1 LAST TOLERANCE 5%
J 0
(4375 -1400);
DISPLAY 0.510638 (4375 -1400);
FORCEPROP 1 LAST VALUE 0
J 2
(4350 -1400);
DISPLAY 0.510638 (4350 -1400);
FORCEPROP 1 LAST MATERIAL CHIP
J 0
(4450 -1400);
DISPLAY 0.510638 (4450 -1400);
FORCEPROP 1 LAST LOCATION R917
J 0
(3975 -1400);
DISPLAY 0.638298 (3975 -1400);
FORCEPROP 1 LASTPIN (4100 -1400) $PN 1
J 0
(4112 -1388);
DISPLAY 0.787234 (4112 -1388);
PAINT MONO (4112 -1388);
FORCEPROP 1 LASTPIN (4300 -1400) $PN 2
J 0
(4262 -1388);
DISPLAY 0.787234 (4262 -1388);
PAINT MONO (4262 -1388);
FORCEPROP 1 LAST PATH I121
J 0
(4150 -1250);
DISPLAY 0.978723 (4150 -1250);
PAINT WHITE (4150 -1250);
DISPLAY INVISIBLE (4150 -1250);
FORCEPROP 2 LAST CDS_LIB pure_quanta
J 0
(4200 -1400);
DISPLAY INVISIBLE (4200 -1400);
FORCEPROP 0 LAST $SEC 1
J 0
(4325 -1350);
DISPLAY 0.680851 (4325 -1350);
PAINT MONO (4325 -1350);
DISPLAY INVISIBLE (4325 -1350);
FORCEPROP 0 LAST CDS_SEC 1
J 0
(4325 -1350);
DISPLAY 1.021277 (4325 -1350);
DISPLAY INVISIBLE (4325 -1350);
FORCEADD OFFPAGE..2
(4250 2650);
FORCEPROP 2 LAST $XR2 240 
J 0
(4679 2650);
DISPLAY 0.638298 (4679 2650);
PAINT MONO (4679 2650);
FORCEPROP 2 LAST $XR1 214 
J 0
(4559 2650);
DISPLAY 0.638298 (4559 2650);
PAINT MONO (4559 2650);
FORCEPROP 2 LAST $XR0 198 
J 0
(4439 2650);
DISPLAY 0.638298 (4439 2650);
PAINT MONO (4439 2650);
FORCEPROP 2 LAST PATH I122
J 0
(4425 2725);
DISPLAY 1.021277 (4425 2725);
DISPLAY INVISIBLE (4425 2725);
FORCEPROP 1 LAST COMMENT_BODY TRUE
J 0
(4205 2555);
DISPLAY 1.170213 (4205 2555);
PAINT GREEN (4205 2555);
DISPLAY INVISIBLE (4205 2555);
FORCEPROP 1 LAST OFFPAGE TRUE
J 0
(4575 2525);
DISPLAY 1.170213 (4575 2525);
PAINT GREEN (4575 2525);
DISPLAY INVISIBLE (4575 2525);
FORCEPROP 2 LAST CDS_LIB standard
J 0
(4250 2650);
DISPLAY INVISIBLE (4250 2650);
FORCEADD MOSFET_NCH_GDS_ESD_PROTECTED..1
(25 -400);
FORCEPROP 1 LAST PART_NUMBER BAM70020002
J 0
(167 -488);
DISPLAY 0.723404 (167 -488);
PAINT GREEN (167 -488);
DISPLAY INVISIBLE (167 -488);
FORCEPROP 2 LAST PART_TYPE SMLF
J 0
(175 -350);
DISPLAY 1.021277 (175 -350);
FORCEPROP 2 LAST VALUE 2N7002K
J 0
(175 -400);
DISPLAY 1.021277 (175 -400);
FORCEPROP 1 LAST MATERIAL IC
J 0
(167 -545);
DISPLAY 0.723404 (167 -545);
FORCEPROP 1 LAST LOCATION Q34
J 0
(167 -436);
DISPLAY 0.723404 (167 -436);
PAINT GREEN (167 -436);
FORCEPROP 0 LASTPIN (50 -200) $PN D
R 1
J 0
(40 -190);
DISPLAY 0.680851 (40 -190);
PAINT MONO (40 -190);
FORCEPROP 0 LASTPIN (-150 -400) $PN G
J 2
(-160 -390);
DISPLAY 0.680851 (-160 -390);
PAINT MONO (-160 -390);
FORCEPROP 0 LASTPIN (50 -600) $PN S
R 1
J 2
(40 -610);
DISPLAY 0.680851 (40 -610);
PAINT MONO (40 -610);
FORCEPROP 2 LAST CDS_LIB pure_quanta
J 0
(25 -400);
DISPLAY INVISIBLE (25 -400);
FORCEPROP 1 LAST CDS_LMAN_SYM_OUTLINE -125,150,125,-150
J 0
(25 -400);
DISPLAY 0.468085 (25 -400);
PAINT GREEN (25 -400);
DISPLAY INVISIBLE (25 -400);
FORCEPROP 1 LAST PATH I123
J 0
(150 -550);
DISPLAY 0.723404 (150 -550);
PAINT GREEN (150 -550);
DISPLAY INVISIBLE (150 -550);
FORCEPROP 1 LAST NEEDS_NO_SIZE TRUE
J 0
(150 -510);
DISPLAY 0.723404 (150 -510);
PAINT GREEN (150 -510);
DISPLAY INVISIBLE (150 -510);
FORCEPROP 0 LAST $SEC 1
J 0
(175 -300);
DISPLAY 0.680851 (175 -300);
PAINT MONO (175 -300);
DISPLAY INVISIBLE (175 -300);
FORCEPROP 0 LAST CDS_SEC 1
J 0
(175 -300);
DISPLAY 1.021277 (175 -300);
DISPLAY INVISIBLE (175 -300);
FORCEADD MOSFET_NCH_GDS_ESD_PROTECTED..1
(25 -1300);
FORCEPROP 1 LAST PART_NUMBER BAM70020002
J 0
(167 -1388);
DISPLAY 0.723404 (167 -1388);
PAINT GREEN (167 -1388);
DISPLAY INVISIBLE (167 -1388);
FORCEPROP 1 LAST MATERIAL IC
J 0
(167 -1445);
DISPLAY 0.723404 (167 -1445);
FORCEPROP 2 LAST PART_TYPE SMLF
J 0
(175 -1250);
DISPLAY 1.021277 (175 -1250);
FORCEPROP 2 LAST VALUE 2N7002K
J 0
(175 -1300);
DISPLAY 1.021277 (175 -1300);
FORCEPROP 1 LAST LOCATION Q35
J 0
(167 -1336);
DISPLAY 0.723404 (167 -1336);
PAINT GREEN (167 -1336);
FORCEPROP 0 LASTPIN (50 -1100) $PN D
R 1
J 0
(40 -1090);
DISPLAY 0.680851 (40 -1090);
PAINT MONO (40 -1090);
FORCEPROP 0 LASTPIN (-150 -1300) $PN G
J 2
(-160 -1290);
DISPLAY 0.680851 (-160 -1290);
PAINT MONO (-160 -1290);
FORCEPROP 0 LASTPIN (50 -1500) $PN S
R 1
J 2
(40 -1510);
DISPLAY 0.680851 (40 -1510);
PAINT MONO (40 -1510);
FORCEPROP 1 LAST NEEDS_NO_SIZE TRUE
J 0
(150 -1410);
DISPLAY 0.723404 (150 -1410);
PAINT GREEN (150 -1410);
DISPLAY INVISIBLE (150 -1410);
FORCEPROP 1 LAST CDS_LMAN_SYM_OUTLINE -125,150,125,-150
J 0
(25 -1300);
DISPLAY 0.468085 (25 -1300);
PAINT GREEN (25 -1300);
DISPLAY INVISIBLE (25 -1300);
FORCEPROP 1 LAST PATH I124
J 0
(150 -1450);
DISPLAY 0.723404 (150 -1450);
PAINT GREEN (150 -1450);
DISPLAY INVISIBLE (150 -1450);
FORCEPROP 2 LAST CDS_LIB pure_quanta
J 0
(25 -1300);
DISPLAY INVISIBLE (25 -1300);
FORCEPROP 0 LAST $SEC 1
J 0
(175 -1200);
DISPLAY 0.680851 (175 -1200);
PAINT MONO (175 -1200);
DISPLAY INVISIBLE (175 -1200);
FORCEPROP 0 LAST CDS_SEC 1
J 0
(175 -1200);
DISPLAY 1.021277 (175 -1200);
DISPLAY INVISIBLE (175 -1200);
FORCEADD Q_RES..2
(-1125 -625);
FORCEPROP 1 LAST PART_NUMBER CS41002FB09
J 0
(-1085 -750);
DISPLAY 0.510638 (-1085 -750);
DISPLAY INVISIBLE (-1085 -750);
FORCEPROP 1 LAST TOLERANCE 1%
J 0
(-1080 -600);
DISPLAY 0.510638 (-1080 -600);
FORCEPROP 1 LAST VALUE 100K
J 0
(-1080 -550);
DISPLAY 0.510638 (-1080 -550);
FORCEPROP 1 LAST WATTAGE 1/16W
J 0
(-1085 -650);
DISPLAY 0.510638 (-1085 -650);
FORCEPROP 1 LAST MATERIAL CHIP
J 0
(-1085 -700);
DISPLAY 0.510638 (-1085 -700);
PAINT RED (-1085 -700);
FORCEPROP 1 LAST PACK_TYPE 0402LF
J 0
(-1085 -800);
DISPLAY 0.510638 (-1085 -800);
FORCEPROP 1 LAST $LOCATION R4712
J 0
(-1080 -500);
DISPLAY 0.978723 (-1080 -500);
FORCEPROP 1 LASTPIN (-1125 -525) $PN 1
J 0
(-1120 -563);
DISPLAY 0.787234 (-1120 -563);
PAINT MONO (-1120 -563);
FORCEPROP 1 LASTPIN (-1125 -725) $PN 2
J 0
(-1120 -715);
DISPLAY 0.787234 (-1120 -715);
PAINT MONO (-1120 -715);
FORCEPROP 1 LAST PATH I125
J 0
(-1075 -450);
DISPLAY 0.978723 (-1075 -450);
PAINT WHITE (-1075 -450);
DISPLAY INVISIBLE (-1075 -450);
FORCEPROP 2 LAST CDS_LIB pure_quanta
J 0
(-1125 -625);
DISPLAY INVISIBLE (-1125 -625);
FORCEPROP 0 LAST CDS_LOCATION R4712
J 0
(-1075 -450);
DISPLAY 1.021277 (-1075 -450);
DISPLAY INVISIBLE (-1075 -450);
FORCEPROP 0 LAST $SEC 1
J 0
(-1075 -450);
DISPLAY 0.680851 (-1075 -450);
PAINT MONO (-1075 -450);
DISPLAY INVISIBLE (-1075 -450);
FORCEPROP 0 LAST CDS_SEC 1
J 0
(-1075 -450);
DISPLAY 1.021277 (-1075 -450);
DISPLAY INVISIBLE (-1075 -450);
FORCEADD UNIVERSAL_GND..1
(-1125 -875);
FORCEPROP 3 LASTPIN (-1125 -825) SIG_NAME GND\g
J 0
(-1115 -815);
DISPLAY 0.659574 (-1115 -815);
PAINT MONO (-1115 -815);
DISPLAY INVISIBLE (-1115 -815);
FORCEPROP 1 LAST HDL_POWER GND
J 1
(-1100 -950);
DISPLAY 0.872340 (-1100 -950);
PAINT GREEN (-1100 -950);
DISPLAY INVISIBLE (-1100 -950);
FORCEPROP 2 LAST ROOM IO_SLOT
J 1
(-1350 -800);
DISPLAY 0.744681 (-1350 -800);
DISPLAY INVISIBLE (-1350 -800);
FORCEPROP 1 LAST PATH I126
J 0
(-1050 -875);
DISPLAY 0.872340 (-1050 -875);
PAINT AQUA (-1050 -875);
DISPLAY INVISIBLE (-1050 -875);
FORCEPROP 2 LAST CDS_LIB logical_power
J 0
(-1125 -875);
DISPLAY INVISIBLE (-1125 -875);
FORCEADD Q_RES..2
(-1125 -1525);
FORCEPROP 1 LAST PART_NUMBER CS41002FB09
J 0
(-1085 -1650);
DISPLAY 0.510638 (-1085 -1650);
DISPLAY INVISIBLE (-1085 -1650);
FORCEPROP 1 LAST VALUE 100K
J 0
(-1080 -1450);
DISPLAY 0.510638 (-1080 -1450);
FORCEPROP 1 LAST PACK_TYPE 0402LF
J 0
(-1085 -1700);
DISPLAY 0.510638 (-1085 -1700);
FORCEPROP 1 LAST TOLERANCE 1%
J 0
(-1080 -1500);
DISPLAY 0.510638 (-1080 -1500);
FORCEPROP 1 LAST WATTAGE 1/16W
J 0
(-1085 -1550);
DISPLAY 0.510638 (-1085 -1550);
FORCEPROP 1 LAST MATERIAL CHIP
J 0
(-1085 -1600);
DISPLAY 0.510638 (-1085 -1600);
PAINT RED (-1085 -1600);
FORCEPROP 1 LAST $LOCATION R4713
J 0
(-1080 -1400);
DISPLAY 0.978723 (-1080 -1400);
FORCEPROP 1 LASTPIN (-1125 -1425) $PN 1
J 0
(-1120 -1463);
DISPLAY 0.787234 (-1120 -1463);
PAINT MONO (-1120 -1463);
FORCEPROP 1 LASTPIN (-1125 -1625) $PN 2
J 0
(-1120 -1615);
DISPLAY 0.787234 (-1120 -1615);
PAINT MONO (-1120 -1615);
FORCEPROP 1 LAST PATH I127
J 0
(-1075 -1350);
DISPLAY 0.978723 (-1075 -1350);
PAINT WHITE (-1075 -1350);
DISPLAY INVISIBLE (-1075 -1350);
FORCEPROP 2 LAST CDS_LIB pure_quanta
J 0
(-1125 -1525);
DISPLAY INVISIBLE (-1125 -1525);
FORCEPROP 0 LAST CDS_LOCATION R4713
J 0
(-1075 -1350);
DISPLAY 1.021277 (-1075 -1350);
DISPLAY INVISIBLE (-1075 -1350);
FORCEPROP 0 LAST $SEC 1
J 0
(-1075 -1350);
DISPLAY 0.680851 (-1075 -1350);
PAINT MONO (-1075 -1350);
DISPLAY INVISIBLE (-1075 -1350);
FORCEPROP 0 LAST CDS_SEC 1
J 0
(-1075 -1350);
DISPLAY 1.021277 (-1075 -1350);
DISPLAY INVISIBLE (-1075 -1350);
FORCEADD UNIVERSAL_GND..1
(-1125 -1775);
FORCEPROP 3 LASTPIN (-1125 -1725) SIG_NAME GND\g
J 0
(-1115 -1715);
DISPLAY 0.659574 (-1115 -1715);
PAINT MONO (-1115 -1715);
DISPLAY INVISIBLE (-1115 -1715);
FORCEPROP 1 LAST HDL_POWER GND
J 1
(-1100 -1850);
DISPLAY 0.872340 (-1100 -1850);
PAINT GREEN (-1100 -1850);
DISPLAY INVISIBLE (-1100 -1850);
FORCEPROP 2 LAST ROOM IO_SLOT
J 1
(-1350 -1700);
DISPLAY 0.744681 (-1350 -1700);
DISPLAY INVISIBLE (-1350 -1700);
FORCEPROP 1 LAST PATH I128
J 0
(-1050 -1775);
DISPLAY 0.872340 (-1050 -1775);
PAINT AQUA (-1050 -1775);
DISPLAY INVISIBLE (-1050 -1775);
FORCEPROP 2 LAST CDS_LIB logical_power
J 0
(-1125 -1775);
DISPLAY INVISIBLE (-1125 -1775);
FORCEADD OFFPAGE..2
(4250 2550);
FORCEPROP 2 LAST $XR0 185 
J 0
(4439 2550);
DISPLAY 0.638298 (4439 2550);
PAINT MONO (4439 2550);
FORCEPROP 2 LAST PATH I13
J 0
(4425 2625);
DISPLAY 1.021277 (4425 2625);
DISPLAY INVISIBLE (4425 2625);
FORCEPROP 1 LAST COMMENT_BODY TRUE
J 0
(4205 2455);
DISPLAY 1.170213 (4205 2455);
PAINT GREEN (4205 2455);
DISPLAY INVISIBLE (4205 2455);
FORCEPROP 1 LAST OFFPAGE TRUE
J 0
(4575 2425);
DISPLAY 1.170213 (4575 2425);
PAINT GREEN (4575 2425);
DISPLAY INVISIBLE (4575 2425);
FORCEPROP 2 LAST CDS_LIB standard
J 0
(4250 2550);
PAINT MONO (4250 2550);
DISPLAY INVISIBLE (4250 2550);
FORCEADD OFFPAGE..1
R 2
(4250 2750);
FORCEPROP 2 LAST $XR2 205 
J 0
(4676 2750);
DISPLAY 0.638298 (4676 2750);
PAINT MONO (4676 2750);
FORCEPROP 2 LAST $XR1 198 
J 0
(4556 2750);
DISPLAY 0.638298 (4556 2750);
PAINT MONO (4556 2750);
FORCEPROP 2 LAST $XR0 131 
J 0
(4436 2750);
DISPLAY 0.638298 (4436 2750);
PAINT MONO (4436 2750);
FORCEPROP 2 LAST PATH I15
J 0
(4425 2825);
DISPLAY 1.021277 (4425 2825);
DISPLAY INVISIBLE (4425 2825);
FORCEPROP 1 LAST COMMENT_BODY TRUE
J 2
(4125 2650);
DISPLAY 1.170213 (4125 2650);
PAINT GREEN (4125 2650);
DISPLAY INVISIBLE (4125 2650);
FORCEPROP 1 LAST OFFPAGE TRUE
J 2
(3925 2625);
DISPLAY 1.170213 (3925 2625);
PAINT GREEN (3925 2625);
DISPLAY INVISIBLE (3925 2625);
FORCEPROP 2 LAST CDS_LIB standard
J 0
(4250 2750);
PAINT MONO (4250 2750);
DISPLAY INVISIBLE (4250 2750);
FORCEADD OFFPAGE..1
R 2
(4250 2850);
FORCEPROP 2 LAST $XR1 198 
J 0
(4556 2850);
DISPLAY 0.638298 (4556 2850);
PAINT MONO (4556 2850);
FORCEPROP 2 LAST $XR0 131 
J 0
(4436 2850);
DISPLAY 0.638298 (4436 2850);
PAINT MONO (4436 2850);
FORCEPROP 2 LAST PATH I16
J 0
(4425 2925);
DISPLAY 1.021277 (4425 2925);
DISPLAY INVISIBLE (4425 2925);
FORCEPROP 1 LAST COMMENT_BODY TRUE
J 2
(4125 2750);
DISPLAY 1.170213 (4125 2750);
PAINT GREEN (4125 2750);
DISPLAY INVISIBLE (4125 2750);
FORCEPROP 1 LAST OFFPAGE TRUE
J 2
(3925 2725);
DISPLAY 1.170213 (3925 2725);
PAINT GREEN (3925 2725);
DISPLAY INVISIBLE (3925 2725);
FORCEPROP 2 LAST CDS_LIB standard
J 0
(4250 2850);
PAINT MONO (4250 2850);
DISPLAY INVISIBLE (4250 2850);
FORCEADD OFFPAGE..1
R 2
(4250 2950);
FORCEPROP 2 LAST $XR1 213 
J 0
(4556 2950);
DISPLAY 0.638298 (4556 2950);
PAINT MONO (4556 2950);
FORCEPROP 2 LAST $XR0 185 
J 0
(4436 2950);
DISPLAY 0.638298 (4436 2950);
PAINT MONO (4436 2950);
FORCEPROP 2 LAST PATH I18
J 0
(4425 3025);
DISPLAY 1.021277 (4425 3025);
DISPLAY INVISIBLE (4425 3025);
FORCEPROP 1 LAST COMMENT_BODY TRUE
J 2
(4125 2850);
DISPLAY 1.170213 (4125 2850);
PAINT GREEN (4125 2850);
DISPLAY INVISIBLE (4125 2850);
FORCEPROP 1 LAST OFFPAGE TRUE
J 2
(3925 2825);
DISPLAY 1.170213 (3925 2825);
PAINT GREEN (3925 2825);
DISPLAY INVISIBLE (3925 2825);
FORCEPROP 2 LAST CDS_LIB standard
J 0
(4250 2950);
PAINT MONO (4250 2950);
DISPLAY INVISIBLE (4250 2950);
FORCEADD OFFPAGE..2
(4250 3000);
FORCEPROP 2 LAST $XR1 205 
J 0
(4559 3000);
DISPLAY 0.638298 (4559 3000);
PAINT MONO (4559 3000);
FORCEPROP 2 LAST $XR0 204 
J 0
(4439 3000);
DISPLAY 0.638298 (4439 3000);
PAINT MONO (4439 3000);
FORCEPROP 2 LAST PATH I19
J 0
(4425 3075);
DISPLAY 1.021277 (4425 3075);
DISPLAY INVISIBLE (4425 3075);
FORCEPROP 1 LAST COMMENT_BODY TRUE
J 0
(4205 2905);
DISPLAY 1.170213 (4205 2905);
PAINT GREEN (4205 2905);
DISPLAY INVISIBLE (4205 2905);
FORCEPROP 1 LAST OFFPAGE TRUE
J 0
(4575 2875);
DISPLAY 1.170213 (4575 2875);
PAINT GREEN (4575 2875);
DISPLAY INVISIBLE (4575 2875);
FORCEPROP 2 LAST CDS_LIB standard
J 0
(4250 3000);
PAINT MONO (4250 3000);
DISPLAY INVISIBLE (4250 3000);
FORCEADD OFFPAGE..1
R 2
(4250 2100);
FORCEPROP 2 LAST $XR1 201 
J 0
(4556 2100);
DISPLAY 0.638298 (4556 2100);
PAINT MONO (4556 2100);
FORCEPROP 2 LAST $XR0 185 
J 0
(4436 2100);
DISPLAY 0.638298 (4436 2100);
PAINT MONO (4436 2100);
FORCEPROP 2 LAST PATH I2
J 0
(4450 2150);
DISPLAY 1.021277 (4450 2150);
DISPLAY INVISIBLE (4450 2150);
FORCEPROP 1 LAST COMMENT_BODY TRUE
J 2
(4125 2000);
DISPLAY 1.170213 (4125 2000);
PAINT GREEN (4125 2000);
DISPLAY INVISIBLE (4125 2000);
FORCEPROP 1 LAST OFFPAGE TRUE
J 2
(3925 1975);
DISPLAY 1.170213 (3925 1975);
PAINT GREEN (3925 1975);
DISPLAY INVISIBLE (3925 1975);
FORCEPROP 2 LAST CDS_LIB standard
J 0
(4250 2100);
PAINT MONO (4250 2100);
DISPLAY INVISIBLE (4250 2100);
FORCEADD OFFPAGE..1
R 2
(4250 3100);
FORCEPROP 2 LAST $XR0 199 
J 0
(4436 3100);
DISPLAY 0.638298 (4436 3100);
PAINT MONO (4436 3100);
FORCEPROP 2 LAST PATH I21
J 0
(4425 3175);
DISPLAY 1.021277 (4425 3175);
DISPLAY INVISIBLE (4425 3175);
FORCEPROP 1 LAST COMMENT_BODY TRUE
J 2
(4125 3000);
DISPLAY 1.170213 (4125 3000);
PAINT GREEN (4125 3000);
DISPLAY INVISIBLE (4125 3000);
FORCEPROP 1 LAST OFFPAGE TRUE
J 2
(3925 2975);
DISPLAY 1.170213 (3925 2975);
PAINT GREEN (3925 2975);
DISPLAY INVISIBLE (3925 2975);
FORCEPROP 2 LAST CDS_LIB standard
J 0
(4250 3100);
PAINT MONO (4250 3100);
DISPLAY INVISIBLE (4250 3100);
FORCEADD OFFPAGE..1
R 2
(4250 3150);
FORCEPROP 2 LAST $XR0 199 
J 0
(4436 3150);
DISPLAY 0.638298 (4436 3150);
PAINT MONO (4436 3150);
FORCEPROP 2 LAST PATH I22
J 0
(4425 3225);
DISPLAY 1.021277 (4425 3225);
DISPLAY INVISIBLE (4425 3225);
FORCEPROP 1 LAST COMMENT_BODY TRUE
J 2
(4125 3050);
DISPLAY 1.170213 (4125 3050);
PAINT GREEN (4125 3050);
DISPLAY INVISIBLE (4125 3050);
FORCEPROP 1 LAST OFFPAGE TRUE
J 2
(3925 3025);
DISPLAY 1.170213 (3925 3025);
PAINT GREEN (3925 3025);
DISPLAY INVISIBLE (3925 3025);
FORCEPROP 2 LAST CDS_LIB standard
J 0
(4250 3150);
PAINT MONO (4250 3150);
DISPLAY INVISIBLE (4250 3150);
FORCEADD OFFPAGE..2
(4250 3300);
FORCEPROP 2 LAST $XR0 213 
J 0
(4439 3300);
DISPLAY 0.638298 (4439 3300);
PAINT MONO (4439 3300);
FORCEPROP 2 LAST PATH I23
J 0
(4425 3375);
DISPLAY 1.021277 (4425 3375);
DISPLAY INVISIBLE (4425 3375);
FORCEPROP 1 LAST COMMENT_BODY TRUE
J 0
(4205 3205);
DISPLAY 1.170213 (4205 3205);
PAINT GREEN (4205 3205);
DISPLAY INVISIBLE (4205 3205);
FORCEPROP 1 LAST OFFPAGE TRUE
J 0
(4575 3175);
DISPLAY 1.170213 (4575 3175);
PAINT GREEN (4575 3175);
DISPLAY INVISIBLE (4575 3175);
FORCEPROP 2 LAST CDS_LIB standard
J 0
(4250 3300);
PAINT MONO (4250 3300);
DISPLAY INVISIBLE (4250 3300);
FORCEADD Q_RES..2
(3625 3550);
FORCEPROP 1 LAST PART_NUMBER CS31002FB08
J 0
(3665 3425);
DISPLAY 0.638298 (3665 3425);
DISPLAY INVISIBLE (3665 3425);
FORCEPROP 1 LAST PACK_TYPE 0402LF
J 0
(3665 3375);
DISPLAY 0.638298 (3665 3375);
FORCEPROP 1 LAST MATERIAL CHIP
J 0
(3665 3475);
DISPLAY 0.638298 (3665 3475);
FORCEPROP 1 LAST WATTAGE 1/16W
J 0
(3665 3525);
DISPLAY 0.638298 (3665 3525);
FORCEPROP 1 LAST VALUE 10K
J 0
(3670 3625);
DISPLAY 0.638298 (3670 3625);
FORCEPROP 1 LAST TOLERANCE 1%
J 0
(3670 3575);
DISPLAY 0.638298 (3670 3575);
FORCEPROP 1 LAST $LOCATION R498
J 0
(3670 3675);
DISPLAY 0.978723 (3670 3675);
FORCEPROP 1 LASTPIN (3625 3650) $PN 1
J 0
(3630 3612);
DISPLAY 0.787234 (3630 3612);
FORCEPROP 1 LASTPIN (3625 3450) $PN 2
J 0
(3630 3460);
DISPLAY 0.787234 (3630 3460);
FORCEPROP 1 LAST PATH I24
J 0
(3675 3725);
DISPLAY 0.978723 (3675 3725);
PAINT WHITE (3675 3725);
DISPLAY INVISIBLE (3675 3725);
FORCEPROP 2 LAST CDS_LIB pure_quanta
J 0
(3625 3550);
PAINT MONO (3625 3550);
DISPLAY INVISIBLE (3625 3550);
FORCEPROP 2 LAST CDS_LOCATION R498
J 0
(3675 3775);
DISPLAY 1.021277 (3675 3775);
DISPLAY INVISIBLE (3675 3775);
FORCEPROP 2 LAST $SEC 1
J 0
(3675 3775);
DISPLAY 0.680851 (3675 3775);
PAINT MONO (3675 3775);
DISPLAY INVISIBLE (3675 3775);
FORCEPROP 2 LAST CDS_SEC 1
J 0
(3675 3775);
DISPLAY 1.021277 (3675 3775);
DISPLAY INVISIBLE (3675 3775);
FORCEADD UNIVERSAL_POWER..1
(3625 3775);
FORCEPROP 3 LASTPIN (3625 3725) SIG_NAME P3V3_AUX\g
J 0
(3635 3735);
DISPLAY 0.659574 (3635 3735);
PAINT MONO (3635 3735);
DISPLAY INVISIBLE (3635 3735);
FORCEPROP 1 LAST HDL_POWER P3V3_AUX
J 1
(3625 3825);
DISPLAY 0.872340 (3625 3825);
PAINT GREEN (3625 3825);
FORCEPROP 1 LAST PATH I25
J 0
(3675 3800);
DISPLAY 0.872340 (3675 3800);
PAINT AQUA (3675 3800);
DISPLAY INVISIBLE (3675 3800);
FORCEPROP 2 LAST CDS_LIB logical_power
J 0
(3625 3775);
PAINT MONO (3625 3775);
DISPLAY INVISIBLE (3625 3775);
FORCEADD EMMITSBURG_REV0P9..7
(1125 2675);
FORCEPROP 1 LAST PART_NUMBER AJ0QV2N0T00
J 0
(-345 3591);
DISPLAY 0.723404 (-345 3591);
PAINT GREEN (-345 3591);
DISPLAY INVISIBLE (-345 3591);
FORCEPROP 2 LAST PART_TYPE SMLF
J 0
(-325 3825);
DISPLAY 1.021277 (-325 3825);
FORCEPROP 2 LAST VALUE GFNOCPU04302300-QV2N-MM#99A1WT
J 0
(-325 3775);
DISPLAY 1.021277 (-325 3775);
FORCEPROP 1 LAST MATERIAL IC
J 0
(-345 3464);
DISPLAY 0.723404 (-345 3464);
PAINT GREEN (-345 3464);
FORCEPROP 1 LAST $LOCATION U4
J 0
(-345 3738);
DISPLAY 0.723404 (-345 3738);
PAINT GREEN (-345 3738);
FORCEPROP 2 LASTPIN (-500 3300) $PN T11
J 2
(-510 3310);
DISPLAY 0.808511 (-510 3310);
FORCEPROP 2 LASTPIN (-500 3200) $PN V11
J 2
(-510 3210);
DISPLAY 0.808511 (-510 3210);
FORCEPROP 2 LASTPIN (2750 2600) $PN BB18
J 0
(2760 2610);
DISPLAY 0.808511 (2760 2610);
FORCEPROP 2 LASTPIN (2750 2650) $PN AU16
J 0
(2760 2660);
DISPLAY 0.808511 (2760 2660);
FORCEPROP 2 LASTPIN (2750 2700) $PN AR16
J 0
(2760 2710);
DISPLAY 0.808511 (2760 2710);
FORCEPROP 2 LASTPIN (2750 2750) $PN AV11
J 0
(2760 2760);
DISPLAY 0.808511 (2760 2760);
FORCEPROP 2 LASTPIN (2750 2800) $PN AU13
J 0
(2760 2810);
DISPLAY 0.808511 (2760 2810);
FORCEPROP 2 LASTPIN (2750 2850) $PN AT18
J 0
(2760 2860);
DISPLAY 0.808511 (2760 2860);
FORCEPROP 2 LASTPIN (2750 2900) $PN AR13
J 0
(2760 2910);
DISPLAY 0.808511 (2760 2910);
FORCEPROP 2 LASTPIN (2750 2950) $PN BA7
J 0
(2760 2960);
DISPLAY 0.808511 (2760 2960);
FORCEPROP 2 LASTPIN (2750 3000) $PN AP15
J 0
(2760 3010);
DISPLAY 0.808511 (2760 3010);
FORCEPROP 2 LASTPIN (2750 3050) $PN AV18
J 0
(2760 3060);
DISPLAY 0.808511 (2760 3060);
FORCEPROP 2 LASTPIN (2750 3100) $PN AW10
J 0
(2760 3110);
DISPLAY 0.808511 (2760 3110);
FORCEPROP 2 LASTPIN (2750 3150) $PN BB8
J 0
(2760 3160);
DISPLAY 0.808511 (2760 3160);
FORCEPROP 2 LASTPIN (2750 3250) $PN BG3
J 0
(2760 3260);
DISPLAY 0.808511 (2760 3260);
FORCEPROP 2 LASTPIN (2750 2100) $PN BD7
J 0
(2760 2110);
DISPLAY 0.808511 (2760 2110);
FORCEPROP 2 LASTPIN (2750 2550) $PN BB15
J 0
(2760 2560);
DISPLAY 0.808511 (2760 2560);
FORCEPROP 2 LASTPIN (2750 2450) $PN AW13
J 0
(2760 2460);
DISPLAY 0.808511 (2760 2460);
FORCEPROP 2 LASTPIN (2750 2500) $PN BA10
J 0
(2760 2510);
DISPLAY 0.808511 (2760 2510);
FORCEPROP 2 LASTPIN (2750 2200) $PN AV15
J 0
(2760 2210);
DISPLAY 0.808511 (2760 2210);
FORCEPROP 2 LASTPIN (2750 2250) $PN BA16
J 0
(2760 2260);
DISPLAY 0.808511 (2760 2260);
FORCEPROP 2 LASTPIN (2750 2350) $PN AW16
J 0
(2760 2360);
DISPLAY 0.808511 (2760 2360);
FORCEPROP 2 LASTPIN (2750 2300) $PN BA13
J 0
(2760 2310);
DISPLAY 0.808511 (2760 2310);
FORCEPROP 2 LASTPIN (2750 2400) $PN BB11
J 0
(2760 2410);
DISPLAY 0.808511 (2760 2410);
FORCEPROP 2 LASTPIN (2750 2050) $PN BF9
J 0
(2760 2060);
DISPLAY 0.808511 (2760 2060);
FORCEPROP 2 LASTPIN (2750 3300) $PN A41
J 0
(2760 3310);
DISPLAY 0.808511 (2760 3310);
FORCEPROP 1 LAST PATH I27
J 0
(1125 2675);
DISPLAY 0.723404 (1125 2675);
PAINT GREEN (1125 2675);
DISPLAY INVISIBLE (1125 2675);
FORCEPROP 2 LAST CDS_LIB pure_quanta
J 0
(1125 2675);
PAINT MONO (1125 2675);
DISPLAY INVISIBLE (1125 2675);
FORCEPROP 1 LAST CDS_LMAN_SYM_OUTLINE -1475,775,1475,-775
J 0
(1125 2675);
DISPLAY 0.468085 (1125 2675);
PAINT GREEN (1125 2675);
DISPLAY INVISIBLE (1125 2675);
FORCEPROP 1 LAST NEEDS_NO_SIZE TRUE
J 0
(1125 2675);
DISPLAY 0.723404 (1125 2675);
PAINT GREEN (1125 2675);
DISPLAY INVISIBLE (1125 2675);
FORCEPROP 2 LAST CDS_LOCATION U4
J 0
(-325 3625);
DISPLAY 1.021277 (-325 3625);
DISPLAY INVISIBLE (-325 3625);
FORCEPROP 2 LAST $SEC 7
J 0
(-325 3875);
DISPLAY 0.680851 (-325 3875);
PAINT MONO (-325 3875);
DISPLAY INVISIBLE (-325 3875);
FORCEPROP 2 LAST CDS_SEC 7
J 0
(-325 3625);
DISPLAY 1.021277 (-325 3625);
DISPLAY INVISIBLE (-325 3625);
FORCEADD OFFPAGE..1
R 2
(4250 2050);
FORCEPROP 2 LAST $XR0 185 
J 0
(4436 2050);
DISPLAY 0.638298 (4436 2050);
PAINT MONO (4436 2050);
FORCEPROP 2 LAST PATH I3
J 0
(4450 2100);
DISPLAY 1.021277 (4450 2100);
DISPLAY INVISIBLE (4450 2100);
FORCEPROP 1 LAST COMMENT_BODY TRUE
J 2
(4125 1950);
DISPLAY 1.170213 (4125 1950);
PAINT GREEN (4125 1950);
DISPLAY INVISIBLE (4125 1950);
FORCEPROP 1 LAST OFFPAGE TRUE
J 2
(3925 1925);
DISPLAY 1.170213 (3925 1925);
PAINT GREEN (3925 1925);
DISPLAY INVISIBLE (3925 1925);
FORCEPROP 2 LAST CDS_LIB standard
J 0
(4250 2050);
DISPLAY INVISIBLE (4250 2050);
FORCEADD OFFPAGE..2
(4250 2200);
FORCEPROP 2 LAST $XR0 185 
J 0
(4439 2200);
DISPLAY 0.638298 (4439 2200);
PAINT MONO (4439 2200);
FORCEPROP 2 LAST PATH I33
J 0
(4425 2275);
DISPLAY 1.021277 (4425 2275);
DISPLAY INVISIBLE (4425 2275);
FORCEPROP 1 LAST COMMENT_BODY TRUE
J 0
(4205 2105);
DISPLAY 1.170213 (4205 2105);
PAINT GREEN (4205 2105);
DISPLAY INVISIBLE (4205 2105);
FORCEPROP 1 LAST OFFPAGE TRUE
J 0
(4575 2075);
DISPLAY 1.170213 (4575 2075);
PAINT GREEN (4575 2075);
DISPLAY INVISIBLE (4575 2075);
FORCEPROP 2 LAST CDS_LIB standard
J 0
(4250 2200);
PAINT MONO (4250 2200);
DISPLAY INVISIBLE (4250 2200);
FORCEADD OFFPAGE..2
(4250 2300);
FORCEPROP 2 LAST $XR0 185 
J 0
(4439 2300);
DISPLAY 0.638298 (4439 2300);
PAINT MONO (4439 2300);
FORCEPROP 2 LAST PATH I34
J 0
(4425 2375);
DISPLAY 1.021277 (4425 2375);
DISPLAY INVISIBLE (4425 2375);
FORCEPROP 1 LAST COMMENT_BODY TRUE
J 0
(4205 2205);
DISPLAY 1.170213 (4205 2205);
PAINT GREEN (4205 2205);
DISPLAY INVISIBLE (4205 2205);
FORCEPROP 1 LAST OFFPAGE TRUE
J 0
(4575 2175);
DISPLAY 1.170213 (4575 2175);
PAINT GREEN (4575 2175);
DISPLAY INVISIBLE (4575 2175);
FORCEPROP 2 LAST CDS_LIB standard
J 0
(4250 2300);
PAINT MONO (4250 2300);
DISPLAY INVISIBLE (4250 2300);
FORCEADD OFFPAGE..2
(4250 2250);
FORCEPROP 2 LAST $XR0 185 
J 0
(4439 2250);
DISPLAY 0.638298 (4439 2250);
PAINT MONO (4439 2250);
FORCEPROP 2 LAST PATH I35
J 0
(4450 2300);
DISPLAY 1.021277 (4450 2300);
DISPLAY INVISIBLE (4450 2300);
FORCEPROP 1 LAST COMMENT_BODY TRUE
J 0
(4205 2155);
DISPLAY 1.170213 (4205 2155);
PAINT GREEN (4205 2155);
DISPLAY INVISIBLE (4205 2155);
FORCEPROP 1 LAST OFFPAGE TRUE
J 0
(4575 2125);
DISPLAY 1.170213 (4575 2125);
PAINT GREEN (4575 2125);
DISPLAY INVISIBLE (4575 2125);
FORCEPROP 2 LAST CDS_LIB standard
J 0
(4250 2250);
PAINT MONO (4250 2250);
DISPLAY INVISIBLE (4250 2250);
FORCEADD OFFPAGE..2
(4250 2350);
FORCEPROP 2 LAST $XR0 185 
J 0
(4439 2350);
DISPLAY 0.638298 (4439 2350);
PAINT MONO (4439 2350);
FORCEPROP 2 LAST PATH I39
J 0
(4425 2425);
DISPLAY 1.021277 (4425 2425);
DISPLAY INVISIBLE (4425 2425);
FORCEPROP 1 LAST COMMENT_BODY TRUE
J 0
(4205 2255);
DISPLAY 1.170213 (4205 2255);
PAINT GREEN (4205 2255);
DISPLAY INVISIBLE (4205 2255);
FORCEPROP 1 LAST OFFPAGE TRUE
J 0
(4575 2225);
DISPLAY 1.170213 (4575 2225);
PAINT GREEN (4575 2225);
DISPLAY INVISIBLE (4575 2225);
FORCEPROP 2 LAST CDS_LIB standard
J 0
(4250 2350);
PAINT MONO (4250 2350);
DISPLAY INVISIBLE (4250 2350);
FORCEADD UNIVERSAL_POWER..1
R 2
(-1400 1300);
FORCEPROP 3 LASTPIN (-1400 1250) SIG_NAME P3V3_RTC_AUX\g
J 0
(-1390 1260);
DISPLAY 0.659574 (-1390 1260);
PAINT MONO (-1390 1260);
DISPLAY INVISIBLE (-1390 1260);
FORCEPROP 1 LAST HDL_POWER P3V3_RTC_AUX
J 1
(-1400 1350);
DISPLAY 1.148936 (-1400 1350);
PAINT GREEN (-1400 1350);
FORCEPROP 1 LAST PATH I53
J 2
(-1450 1325);
DISPLAY 0.872340 (-1450 1325);
PAINT AQUA (-1450 1325);
DISPLAY INVISIBLE (-1450 1325);
FORCEPROP 2 LAST CDS_LIB logical_power
J 0
(-1400 1300);
DISPLAY INVISIBLE (-1400 1300);
FORCEADD UNIVERSAL_POWER..1
R 2
(4500 900);
FORCEPROP 3 LASTPIN (4500 850) SIG_NAME P3V3_AUX\g
J 0
(4510 860);
DISPLAY 0.659574 (4510 860);
PAINT MONO (4510 860);
DISPLAY INVISIBLE (4510 860);
FORCEPROP 1 LAST HDL_POWER P3V3_AUX
J 1
(4500 950);
DISPLAY 1.148936 (4500 950);
PAINT GREEN (4500 950);
FORCEPROP 1 LAST PATH I56
J 2
(4450 925);
DISPLAY 0.872340 (4450 925);
PAINT AQUA (4450 925);
DISPLAY INVISIBLE (4450 925);
FORCEPROP 2 LAST CDS_LIB logical_power
J 0
(4500 900);
DISPLAY INVISIBLE (4500 900);
FORCEADD OFFPAGE..2
(-500 850);
FORCEPROP 2 LAST $XR0 185 
J 0
(-311 850);
DISPLAY 0.638298 (-311 850);
PAINT MONO (-311 850);
FORCEPROP 2 LAST PATH I57
J 0
(-300 900);
DISPLAY 1.021277 (-300 900);
DISPLAY INVISIBLE (-300 900);
FORCEPROP 1 LAST COMMENT_BODY TRUE
J 0
(-545 755);
DISPLAY 1.170213 (-545 755);
PAINT GREEN (-545 755);
DISPLAY INVISIBLE (-545 755);
FORCEPROP 1 LAST OFFPAGE TRUE
J 0
(-175 725);
DISPLAY 1.170213 (-175 725);
PAINT GREEN (-175 725);
DISPLAY INVISIBLE (-175 725);
FORCEPROP 2 LAST CDS_LIB standard
J 0
(-500 850);
DISPLAY INVISIBLE (-500 850);
FORCEADD UNIVERSAL_POWER..1
R 2
(5125 600);
FORCEPROP 3 LASTPIN (5125 550) SIG_NAME P3V3_RTC_AUX\g
J 0
(5135 560);
DISPLAY 0.659574 (5135 560);
PAINT MONO (5135 560);
DISPLAY INVISIBLE (5135 560);
FORCEPROP 1 LAST HDL_POWER P3V3_RTC_AUX
J 1
(5125 650);
DISPLAY 1.148936 (5125 650);
PAINT GREEN (5125 650);
FORCEPROP 1 LAST PATH I59
J 2
(5075 625);
DISPLAY 0.872340 (5075 625);
PAINT AQUA (5075 625);
DISPLAY INVISIBLE (5075 625);
FORCEPROP 2 LAST CDS_LIB logical_power
J 0
(5125 600);
DISPLAY INVISIBLE (5125 600);
FORCEADD Q_RES..1
(3625 350);
FORCEPROP 1 LAST PART_NUMBER CS21002FB06
J 0
(3500 450);
DISPLAY 0.510638 (3500 450);
DISPLAY INVISIBLE (3500 450);
FORCEPROP 1 LAST WATTAGE 1/16W
J 2
(3850 500);
DISPLAY 0.510638 (3850 500);
FORCEPROP 1 LAST PACK_TYPE 0402LF
J 0
(3500 500);
DISPLAY 0.510638 (3500 500);
FORCEPROP 1 LAST MATERIAL CHIP
J 0
(3900 350);
DISPLAY 0.638298 (3900 350);
FORCEPROP 1 LAST VALUE 1K
J 2
(3800 350);
DISPLAY 0.638298 (3800 350);
FORCEPROP 1 LAST TOLERANCE 1%
J 0
(3825 350);
DISPLAY 0.638298 (3825 350);
FORCEPROP 1 LAST $LOCATION R1203
J 0
(3425 350);
DISPLAY 0.638298 (3425 350);
FORCEPROP 1 LASTPIN (3525 350) $PN 1
J 0
(3537 362);
DISPLAY 0.787234 (3537 362);
FORCEPROP 1 LASTPIN (3725 350) $PN 2
J 0
(3687 362);
DISPLAY 0.787234 (3687 362);
FORCEPROP 1 LAST PATH I62
J 0
(3575 500);
DISPLAY 0.978723 (3575 500);
PAINT WHITE (3575 500);
DISPLAY INVISIBLE (3575 500);
FORCEPROP 2 LAST CDS_LIB pure_quanta
J 0
(3625 350);
PAINT MONO (3625 350);
DISPLAY INVISIBLE (3625 350);
FORCEPROP 2 LAST CDS_LOCATION R1203
J 0
(3575 550);
DISPLAY 1.021277 (3575 550);
DISPLAY INVISIBLE (3575 550);
FORCEPROP 2 LAST $SEC 1
J 0
(3575 550);
DISPLAY 0.680851 (3575 550);
PAINT MONO (3575 550);
DISPLAY INVISIBLE (3575 550);
FORCEPROP 2 LAST CDS_SEC 1
J 0
(3575 550);
DISPLAY 1.021277 (3575 550);
DISPLAY INVISIBLE (3575 550);
FORCEADD CONN2_AAABAT029Y19..1
R 2
(2725 350);
FORCEPROP 1 LAST PART_NUMBER DFHS02FR062
J 2
(2769 534);
DISPLAY 0.723404 (2769 534);
PAINT GREEN (2769 534);
DISPLAY INVISIBLE (2769 534);
FORCEPROP 2 LAST VALUE CONN2_AAA-BAT-029-Y19
J 2
(2975 575);
DISPLAY 0.680851 (2975 575);
FORCEPROP 2 LAST PART_TYPE THLF
J 0
(2675 625);
DISPLAY 0.638298 (2675 625);
FORCEPROP 1 LAST MATERIAL IO
J 2
(2769 407);
DISPLAY 0.723404 (2769 407);
PAINT GREEN (2769 407);
FORCEPROP 1 LAST $LOCATION BT1
J 2
(2769 681);
DISPLAY 0.723404 (2769 681);
PAINT GREEN (2769 681);
FORCEPROP 0 LASTPIN (2925 350) $PN 1
J 0
(2935 360);
DISPLAY 0.680851 (2935 360);
PAINT MONO (2935 360);
FORCEPROP 0 LASTPIN (2525 350) $PN 2
J 2
(2515 360);
DISPLAY 0.680851 (2515 360);
PAINT MONO (2515 360);
FORCEPROP 1 LAST PATH I63
J 2
(2725 350);
DISPLAY 0.723404 (2725 350);
PAINT GREEN (2725 350);
DISPLAY INVISIBLE (2725 350);
FORCEPROP 2 LAST CDS_LIB pure_quanta
J 0
(2725 350);
DISPLAY INVISIBLE (2725 350);
FORCEPROP 1 LAST CDS_LMAN_SYM_OUTLINE -50,50,50,-50
J 2
(2725 350);
DISPLAY 0.468085 (2725 350);
PAINT GREEN (2725 350);
DISPLAY INVISIBLE (2725 350);
FORCEPROP 1 LAST NEEDS_NO_SIZE TRUE
J 2
(2725 350);
DISPLAY 0.723404 (2725 350);
PAINT GREEN (2725 350);
DISPLAY INVISIBLE (2725 350);
FORCEPROP 2 LAST CDS_LOCATION BT1
J 0
(2700 800);
DISPLAY 1.021277 (2700 800);
DISPLAY INVISIBLE (2700 800);
FORCEPROP 0 LAST $SEC 1
J 0
(2775 725);
DISPLAY 0.680851 (2775 725);
PAINT MONO (2775 725);
DISPLAY INVISIBLE (2775 725);
FORCEPROP 2 LAST CDS_SEC 1
J 0
(2700 800);
DISPLAY 1.021277 (2700 800);
DISPLAY INVISIBLE (2700 800);
FORCEADD BAS70057F..1
R 7
(4700 400);
FORCEPROP 1 LAST PART_NUMBER BC0BAS70Z01
J 0
(4560 500);
DISPLAY 0.468085 (4560 500);
PAINT GREEN (4560 500);
DISPLAY INVISIBLE (4560 500);
FORCEPROP 2 LAST VALUE BAS70-05-7-F
J 0
(4550 625);
DISPLAY 0.361702 (4550 625);
FORCEPROP 2 LAST PART_TYPE SMLF
J 0
(4550 600);
DISPLAY 0.361702 (4550 600);
FORCEPROP 1 LAST MATERIAL IC
J 0
(4560 525);
DISPLAY 0.468085 (4560 525);
PAINT GREEN (4560 525);
FORCEPROP 1 LAST $LOCATION U62
J 0
(4555 550);
DISPLAY 0.468085 (4555 550);
PAINT GREEN (4555 550);
FORCEPROP 2 LASTPIN (4600 450) $PN 2
J 2
(4590 460);
DISPLAY 0.808511 (4590 460);
FORCEPROP 2 LASTPIN (4600 350) $PN 1
J 2
(4590 360);
DISPLAY 0.808511 (4590 360);
FORCEPROP 2 LASTPIN (4800 400) $PN 3
J 0
(4810 410);
DISPLAY 0.808511 (4810 410);
FORCEPROP 1 LAST PATH I64
R 1
J 0
(4605 575);
DISPLAY 0.723404 (4605 575);
PAINT GREEN (4605 575);
DISPLAY INVISIBLE (4605 575);
FORCEPROP 1 LAST NEEDS_NO_SIZE TRUE
R 1
J 0
(4700 400);
DISPLAY 0.468085 (4700 400);
PAINT GREEN (4700 400);
DISPLAY INVISIBLE (4700 400);
FORCEPROP 1 LAST CDS_LMAN_SYM_OUTLINE -75,50,75,-25
R 1
J 0
(4700 400);
DISPLAY 0.468085 (4700 400);
PAINT GREEN (4700 400);
DISPLAY INVISIBLE (4700 400);
FORCEPROP 2 LAST CDS_LIB pure_quanta
J 0
(4700 400);
PAINT MONO (4700 400);
DISPLAY INVISIBLE (4700 400);
FORCEPROP 2 LAST CDS_LOCATION U62
J 0
(4550 650);
DISPLAY 1.021277 (4550 650);
DISPLAY INVISIBLE (4550 650);
FORCEPROP 2 LAST $SEC 1
J 0
(4550 650);
DISPLAY 0.680851 (4550 650);
PAINT MONO (4550 650);
DISPLAY INVISIBLE (4550 650);
FORCEPROP 2 LAST CDS_SEC 1
J 0
(4550 650);
DISPLAY 1.021277 (4550 650);
DISPLAY INVISIBLE (4550 650);
FORCEADD Q_CAP..1
(5125 150);
FORCEPROP 1 LAST PART_NUMBER CH5104KEB02
J 0
(5175 0);
DISPLAY 0.638298 (5175 0);
DISPLAY INVISIBLE (5175 0);
FORCEPROP 1 LAST TOLERANCE 10%
J 0
(5175 100);
DISPLAY 0.638298 (5175 100);
FORCEPROP 1 LAST VOLTAGE 25V
J 0
(5175 150);
DISPLAY 0.638298 (5175 150);
FORCEPROP 1 LAST VALUE 1UF
J 0
(5175 200);
DISPLAY 0.638298 (5175 200);
FORCEPROP 1 LAST MATERIAL X6S
J 0
(5175 50);
DISPLAY 0.638298 (5175 50);
FORCEPROP 1 LAST PACK_TYPE C0402
J 0
(5175 -50);
DISPLAY 0.638298 (5175 -50);
FORCEPROP 1 LAST $LOCATION C611
J 0
(5175 250);
DISPLAY 0.978723 (5175 250);
FORCEPROP 1 LASTPIN (5125 250) $PN 1
J 0
(5135 230);
DISPLAY 0.787234 (5135 230);
FORCEPROP 1 LASTPIN (5125 50) $PN 2
J 0
(5135 30);
DISPLAY 0.787234 (5135 30);
FORCEPROP 1 LAST PATH I65
J 0
(5175 300);
DISPLAY 0.978723 (5175 300);
PAINT WHITE (5175 300);
DISPLAY INVISIBLE (5175 300);
FORCEPROP 2 LAST CDS_LIB pure_quanta
J 0
(5125 150);
PAINT MONO (5125 150);
DISPLAY INVISIBLE (5125 150);
FORCEPROP 2 LAST CDS_LOCATION C611
J 0
(5175 350);
DISPLAY 1.021277 (5175 350);
DISPLAY INVISIBLE (5175 350);
FORCEPROP 2 LAST $SEC 1
J 0
(5175 350);
DISPLAY 0.680851 (5175 350);
PAINT MONO (5175 350);
DISPLAY INVISIBLE (5175 350);
FORCEPROP 2 LAST CDS_SEC 1
J 0
(5175 350);
DISPLAY 1.021277 (5175 350);
DISPLAY INVISIBLE (5175 350);
FORCEADD UNIVERSAL_GND..1
(2400 150);
FORCEPROP 3 LASTPIN (2400 200) SIG_NAME GND\g
J 0
(2410 210);
DISPLAY 0.659574 (2410 210);
PAINT MONO (2410 210);
DISPLAY INVISIBLE (2410 210);
FORCEPROP 2 LAST ROOM IO_SLOT
J 1
(2175 225);
DISPLAY 0.744681 (2175 225);
DISPLAY INVISIBLE (2175 225);
FORCEPROP 1 LAST PATH I66
J 0
(2475 150);
DISPLAY 0.872340 (2475 150);
PAINT AQUA (2475 150);
DISPLAY INVISIBLE (2475 150);
FORCEPROP 1 LAST HDL_POWER GND
J 1
(2425 75);
DISPLAY 0.872340 (2425 75);
PAINT GREEN (2425 75);
DISPLAY INVISIBLE (2425 75);
FORCEPROP 2 LAST CDS_LIB logical_power
J 0
(2400 150);
PAINT MONO (2400 150);
DISPLAY INVISIBLE (2400 150);
FORCEADD UNIVERSAL_GND..1
(5125 -75);
FORCEPROP 3 LASTPIN (5125 -25) SIG_NAME GND\g
J 0
(5135 -15);
DISPLAY 0.659574 (5135 -15);
PAINT MONO (5135 -15);
DISPLAY INVISIBLE (5135 -15);
FORCEPROP 2 LAST ROOM IO_SLOT
J 1
(4900 0);
DISPLAY 0.744681 (4900 0);
DISPLAY INVISIBLE (4900 0);
FORCEPROP 1 LAST PATH I67
J 0
(5200 -75);
DISPLAY 0.872340 (5200 -75);
PAINT AQUA (5200 -75);
DISPLAY INVISIBLE (5200 -75);
FORCEPROP 1 LAST HDL_POWER GND
J 1
(5150 -150);
DISPLAY 0.872340 (5150 -150);
PAINT GREEN (5150 -150);
DISPLAY INVISIBLE (5150 -150);
FORCEPROP 2 LAST CDS_LIB logical_power
J 0
(5125 -75);
PAINT MONO (5125 -75);
DISPLAY INVISIBLE (5125 -75);
FORCEADD Q_CAP..1
(-1400 675);
FORCEPROP 1 LAST PART_NUMBER CH5104KEB02
J 0
(-1350 525);
DISPLAY 0.638298 (-1350 525);
DISPLAY INVISIBLE (-1350 525);
FORCEPROP 1 LAST VOLTAGE 25V
J 0
(-1350 675);
DISPLAY 0.638298 (-1350 675);
FORCEPROP 1 LAST MATERIAL X6S
J 0
(-1350 575);
DISPLAY 0.638298 (-1350 575);
FORCEPROP 1 LAST TOLERANCE 10%
J 0
(-1350 625);
DISPLAY 0.638298 (-1350 625);
FORCEPROP 1 LAST VALUE 1UF
J 0
(-1350 725);
DISPLAY 0.638298 (-1350 725);
FORCEPROP 1 LAST PACK_TYPE C0402
J 0
(-1350 475);
DISPLAY 0.638298 (-1350 475);
FORCEPROP 1 LAST $LOCATION C610
J 0
(-1350 775);
DISPLAY 0.978723 (-1350 775);
FORCEPROP 1 LASTPIN (-1400 775) $PN 1
J 0
(-1390 755);
DISPLAY 0.787234 (-1390 755);
FORCEPROP 1 LASTPIN (-1400 575) $PN 2
J 0
(-1390 555);
DISPLAY 0.787234 (-1390 555);
FORCEPROP 1 LAST PATH I68
J 0
(-1350 825);
DISPLAY 0.978723 (-1350 825);
PAINT WHITE (-1350 825);
DISPLAY INVISIBLE (-1350 825);
FORCEPROP 2 LAST CDS_LIB pure_quanta
J 0
(-1400 675);
PAINT MONO (-1400 675);
DISPLAY INVISIBLE (-1400 675);
FORCEPROP 2 LAST CDS_LOCATION C610
J 0
(-1350 875);
DISPLAY 1.021277 (-1350 875);
DISPLAY INVISIBLE (-1350 875);
FORCEPROP 2 LAST $SEC 1
J 0
(-1350 875);
DISPLAY 0.680851 (-1350 875);
PAINT MONO (-1350 875);
DISPLAY INVISIBLE (-1350 875);
FORCEPROP 2 LAST CDS_SEC 1
J 0
(-1350 875);
DISPLAY 1.021277 (-1350 875);
DISPLAY INVISIBLE (-1350 875);
FORCEADD UNIVERSAL_GND..1
(-1400 425);
FORCEPROP 3 LASTPIN (-1400 475) SIG_NAME GND\g
J 0
(-1390 485);
DISPLAY 0.659574 (-1390 485);
PAINT MONO (-1390 485);
DISPLAY INVISIBLE (-1390 485);
FORCEPROP 2 LAST ROOM IO_SLOT
J 1
(-1625 500);
DISPLAY 0.744681 (-1625 500);
DISPLAY INVISIBLE (-1625 500);
FORCEPROP 1 LAST PATH I69
J 0
(-1325 425);
DISPLAY 0.872340 (-1325 425);
PAINT AQUA (-1325 425);
DISPLAY INVISIBLE (-1325 425);
FORCEPROP 1 LAST HDL_POWER GND
J 1
(-1375 350);
DISPLAY 0.872340 (-1375 350);
PAINT GREEN (-1375 350);
DISPLAY INVISIBLE (-1375 350);
FORCEPROP 2 LAST CDS_LIB logical_power
J 0
(-1400 425);
PAINT MONO (-1400 425);
DISPLAY INVISIBLE (-1400 425);
FORCEADD Q_RES..2
(-1400 1075);
FORCEPROP 1 LAST PART_NUMBER CS32002FB06
J 0
(-1360 950);
DISPLAY 0.638298 (-1360 950);
DISPLAY INVISIBLE (-1360 950);
FORCEPROP 1 LAST TOLERANCE 1%
J 0
(-1355 1100);
DISPLAY 0.638298 (-1355 1100);
FORCEPROP 1 LAST VALUE 20K
J 0
(-1355 1150);
DISPLAY 0.638298 (-1355 1150);
FORCEPROP 1 LAST MATERIAL CHIP
J 0
(-1360 1000);
DISPLAY 0.638298 (-1360 1000);
FORCEPROP 1 LAST PACK_TYPE 0402LF
J 0
(-1360 900);
DISPLAY 0.638298 (-1360 900);
FORCEPROP 1 LAST WATTAGE 1/16W
J 0
(-1360 1050);
DISPLAY 0.638298 (-1360 1050);
FORCEPROP 1 LAST $LOCATION R1202
J 0
(-1355 1200);
DISPLAY 0.978723 (-1355 1200);
FORCEPROP 1 LASTPIN (-1400 1175) $PN 1
J 0
(-1395 1137);
DISPLAY 0.787234 (-1395 1137);
FORCEPROP 1 LASTPIN (-1400 975) $PN 2
J 0
(-1395 985);
DISPLAY 0.787234 (-1395 985);
FORCEPROP 1 LAST PATH I70
J 0
(-1350 1250);
DISPLAY 0.978723 (-1350 1250);
PAINT WHITE (-1350 1250);
DISPLAY INVISIBLE (-1350 1250);
FORCEPROP 2 LAST CDS_LIB pure_quanta
J 0
(-1400 1075);
PAINT MONO (-1400 1075);
DISPLAY INVISIBLE (-1400 1075);
FORCEPROP 2 LAST CDS_LOCATION R1202
J 0
(-1350 1300);
DISPLAY 1.021277 (-1350 1300);
DISPLAY INVISIBLE (-1350 1300);
FORCEPROP 2 LAST $SEC 1
J 0
(-1350 1300);
DISPLAY 0.680851 (-1350 1300);
PAINT MONO (-1350 1300);
DISPLAY INVISIBLE (-1350 1300);
FORCEPROP 2 LAST CDS_SEC 1
J 0
(-1350 1300);
DISPLAY 1.021277 (-1350 1300);
DISPLAY INVISIBLE (-1350 1300);
FORCEADD OFFPAGE..1
R 2
(4250 2800);
FORCEPROP 2 LAST $XR0 198 
J 0
(4436 2800);
DISPLAY 0.638298 (4436 2800);
PAINT MONO (4436 2800);
FORCEPROP 2 LAST PATH I71
J 0
(4450 2850);
DISPLAY 1.021277 (4450 2850);
DISPLAY INVISIBLE (4450 2850);
FORCEPROP 1 LAST COMMENT_BODY TRUE
J 2
(4125 2700);
DISPLAY 1.170213 (4125 2700);
PAINT GREEN (4125 2700);
DISPLAY INVISIBLE (4125 2700);
FORCEPROP 1 LAST OFFPAGE TRUE
J 2
(3925 2675);
DISPLAY 1.170213 (3925 2675);
PAINT GREEN (3925 2675);
DISPLAY INVISIBLE (3925 2675);
FORCEPROP 2 LAST CDS_LIB standard
J 0
(4250 2800);
PAINT MONO (4250 2800);
DISPLAY INVISIBLE (4250 2800);
FORCEADD OFFPAGE..2
(4250 2400);
FORCEPROP 2 LAST $XR0 185 
J 0
(4439 2400);
DISPLAY 0.638298 (4439 2400);
PAINT MONO (4439 2400);
FORCEPROP 2 LAST PATH I73
J 0
(4425 2475);
DISPLAY 1.021277 (4425 2475);
DISPLAY INVISIBLE (4425 2475);
FORCEPROP 1 LAST COMMENT_BODY TRUE
J 0
(4205 2305);
DISPLAY 1.170213 (4205 2305);
PAINT GREEN (4205 2305);
DISPLAY INVISIBLE (4205 2305);
FORCEPROP 1 LAST OFFPAGE TRUE
J 0
(4575 2275);
DISPLAY 1.170213 (4575 2275);
PAINT GREEN (4575 2275);
DISPLAY INVISIBLE (4575 2275);
FORCEPROP 2 LAST CDS_LIB standard
J 0
(4250 2400);
PAINT MONO (4250 2400);
DISPLAY INVISIBLE (4250 2400);
FORCEADD OFFPAGE..1
R 2
(4250 2700);
FORCEPROP 2 LAST $XR0 200 
J 0
(4436 2700);
DISPLAY 0.638298 (4436 2700);
PAINT MONO (4436 2700);
FORCEPROP 2 LAST PATH I74
J 0
(4600 2750);
DISPLAY 1.021277 (4600 2750);
DISPLAY INVISIBLE (4600 2750);
FORCEPROP 1 LAST COMMENT_BODY TRUE
J 2
(4125 2600);
DISPLAY 1.170213 (4125 2600);
PAINT GREEN (4125 2600);
DISPLAY INVISIBLE (4125 2600);
FORCEPROP 1 LAST OFFPAGE TRUE
J 2
(3925 2575);
DISPLAY 1.170213 (3925 2575);
PAINT GREEN (3925 2575);
DISPLAY INVISIBLE (3925 2575);
FORCEPROP 2 LAST CDS_LIB standard
J 0
(4250 2700);
PAINT MONO (4250 2700);
DISPLAY INVISIBLE (4250 2700);
FORCEADD OFFPAGE..1
R 2
(4250 2600);
FORCEPROP 2 LAST $XR0 200 
J 0
(4436 2600);
DISPLAY 0.638298 (4436 2600);
PAINT MONO (4436 2600);
FORCEPROP 2 LAST PATH I75
J 0
(4600 2650);
DISPLAY 1.021277 (4600 2650);
DISPLAY INVISIBLE (4600 2650);
FORCEPROP 1 LAST COMMENT_BODY TRUE
J 2
(4125 2500);
DISPLAY 1.170213 (4125 2500);
PAINT GREEN (4125 2500);
DISPLAY INVISIBLE (4125 2500);
FORCEPROP 1 LAST OFFPAGE TRUE
J 2
(3925 2475);
DISPLAY 1.170213 (3925 2475);
PAINT GREEN (3925 2475);
DISPLAY INVISIBLE (3925 2475);
FORCEPROP 2 LAST CDS_LIB standard
J 0
(4250 2600);
PAINT MONO (4250 2600);
DISPLAY INVISIBLE (4250 2600);
FORCEADD OFFPAGE..2
(4250 2900);
FORCEPROP 2 LAST $XR0 185 
J 0
(4439 2900);
DISPLAY 0.638298 (4439 2900);
PAINT MONO (4439 2900);
FORCEPROP 2 LAST PATH I76
J 0
(4450 2950);
DISPLAY 1.021277 (4450 2950);
DISPLAY INVISIBLE (4450 2950);
FORCEPROP 1 LAST COMMENT_BODY TRUE
J 0
(4205 2805);
DISPLAY 1.170213 (4205 2805);
PAINT GREEN (4205 2805);
DISPLAY INVISIBLE (4205 2805);
FORCEPROP 1 LAST OFFPAGE TRUE
J 0
(4575 2775);
DISPLAY 1.170213 (4575 2775);
PAINT GREEN (4575 2775);
DISPLAY INVISIBLE (4575 2775);
FORCEPROP 2 LAST CDS_LIB standard
J 0
(4250 2900);
PAINT MONO (4250 2900);
DISPLAY INVISIBLE (4250 2900);
FORCEADD OFFPAGE..2
(6125 -500);
FORCEPROP 2 LAST $XR1 185 
J 0
(6434 -500);
DISPLAY 0.638298 (6434 -500);
PAINT MONO (6434 -500);
FORCEPROP 2 LAST $XR0 213 
J 0
(6314 -500);
DISPLAY 0.638298 (6314 -500);
PAINT MONO (6314 -500);
FORCEPROP 2 LAST PATH I78
J 0
(6325 -450);
DISPLAY 1.021277 (6325 -450);
DISPLAY INVISIBLE (6325 -450);
FORCEPROP 1 LAST COMMENT_BODY TRUE
J 0
(6080 -595);
DISPLAY 0.872340 (6080 -595);
PAINT GREEN (6080 -595);
DISPLAY INVISIBLE (6080 -595);
FORCEPROP 1 LAST OFFPAGE TRUE
J 0
(6450 -625);
DISPLAY 0.872340 (6450 -625);
DISPLAY INVISIBLE (6450 -625);
FORCEPROP 2 LAST CDS_LIB standard
J 0
(6125 -500);
DISPLAY INVISIBLE (6125 -500);
FORCEADD OFFPAGE..1
(2525 -500);
FORCEPROP 2 LAST $XR0 185 
J 0
(2273 -500);
DISPLAY 0.638298 (2273 -500);
PAINT MONO (2273 -500);
FORCEPROP 2 LAST PATH I79
J 0
(2250 -450);
DISPLAY 1.021277 (2250 -450);
DISPLAY INVISIBLE (2250 -450);
FORCEPROP 1 LAST COMMENT_BODY TRUE
J 0
(2650 -600);
DISPLAY 0.872340 (2650 -600);
PAINT GREEN (2650 -600);
DISPLAY INVISIBLE (2650 -600);
FORCEPROP 1 LAST OFFPAGE TRUE
J 0
(2850 -625);
DISPLAY 0.872340 (2850 -625);
DISPLAY INVISIBLE (2850 -625);
FORCEPROP 2 LAST CDS_LIB standard
J 0
(2525 -500);
DISPLAY INVISIBLE (2525 -500);
FORCEADD Q_RES..1
(4225 -500);
FORCEPROP 1 LAST PART_NUMBER CS00002JB13
J 0
(4175 -450);
DISPLAY 0.404255 (4175 -450);
DISPLAY INVISIBLE (4175 -450);
FORCEPROP 1 LAST PACK_TYPE 0402LF
J 0
(4175 -425);
DISPLAY 0.404255 (4175 -425);
FORCEPROP 1 LAST MATERIAL CHIP
J 0
(4475 -500);
DISPLAY 0.510638 (4475 -500);
FORCEPROP 1 LAST VALUE 0
J 2
(4375 -500);
DISPLAY 0.510638 (4375 -500);
FORCEPROP 1 LAST WATTAGE 1/16W
J 2
(4400 -425);
DISPLAY 0.404255 (4400 -425);
FORCEPROP 1 LAST TOLERANCE 5%
J 0
(4400 -500);
DISPLAY 0.510638 (4400 -500);
FORCEPROP 1 LAST $LOCATION R1461
J 0
(3950 -500);
DISPLAY 0.638298 (3950 -500);
FORCEPROP 1 LASTPIN (4125 -500) $PN 1
J 0
(4137 -488);
DISPLAY 0.787234 (4137 -488);
FORCEPROP 1 LASTPIN (4325 -500) $PN 2
J 0
(4287 -488);
DISPLAY 0.787234 (4287 -488);
FORCEPROP 1 LAST PATH I80
J 0
(4175 -350);
DISPLAY 0.978723 (4175 -350);
PAINT WHITE (4175 -350);
DISPLAY INVISIBLE (4175 -350);
FORCEPROP 2 LAST CDS_LIB pure_quanta
J 0
(4225 -500);
PAINT MONO (4225 -500);
DISPLAY INVISIBLE (4225 -500);
FORCEPROP 2 LAST CDS_LOCATION R1461
J 0
(4175 -300);
DISPLAY 1.021277 (4175 -300);
DISPLAY INVISIBLE (4175 -300);
FORCEPROP 2 LAST $SEC 1
J 0
(4175 -300);
DISPLAY 0.680851 (4175 -300);
PAINT MONO (4175 -300);
DISPLAY INVISIBLE (4175 -300);
FORCEPROP 2 LAST CDS_SEC 1
J 0
(4175 -300);
DISPLAY 1.021277 (4175 -300);
DISPLAY INVISIBLE (4175 -300);
FORCEADD OFFPAGE..1
(-1375 -400);
FORCEPROP 2 LAST $XR0 222 
J 0
(-1627 -400);
DISPLAY 0.638298 (-1627 -400);
PAINT MONO (-1627 -400);
FORCEPROP 2 LAST PATH I82
J 0
(-1675 -350);
DISPLAY 1.021277 (-1675 -350);
DISPLAY INVISIBLE (-1675 -350);
FORCEPROP 1 LAST COMMENT_BODY TRUE
J 0
(-1250 -500);
DISPLAY 0.872340 (-1250 -500);
PAINT GREEN (-1250 -500);
DISPLAY INVISIBLE (-1250 -500);
FORCEPROP 1 LAST OFFPAGE TRUE
J 0
(-1050 -525);
DISPLAY 0.872340 (-1050 -525);
DISPLAY INVISIBLE (-1050 -525);
FORCEPROP 2 LAST CDS_LIB standard
J 0
(-1375 -400);
PAINT MONO (-1375 -400);
DISPLAY INVISIBLE (-1375 -400);
FORCEADD UNIVERSAL_GND..1
(50 -775);
FORCEPROP 3 LASTPIN (50 -725) SIG_NAME GND\g
J 0
(60 -715);
DISPLAY 0.659574 (60 -715);
PAINT MONO (60 -715);
DISPLAY INVISIBLE (60 -715);
FORCEPROP 2 LAST CDS_LIB logical_power
J 0
(50 -775);
PAINT MONO (50 -775);
DISPLAY INVISIBLE (50 -775);
FORCEPROP 1 LAST PATH I83
J 0
(125 -775);
DISPLAY 0.872340 (125 -775);
PAINT AQUA (125 -775);
DISPLAY INVISIBLE (125 -775);
FORCEPROP 1 LAST HDL_POWER GND
J 1
(75 -850);
DISPLAY 0.872340 (75 -850);
PAINT GREEN (75 -850);
DISPLAY INVISIBLE (75 -850);
FORCEPROP 2 LAST ROOM IO_SLOT
J 1
(-175 -700);
DISPLAY 0.744681 (-175 -700);
DISPLAY INVISIBLE (-175 -700);
FORCEADD OFFPAGE..2
(775 -25);
FORCEPROP 2 LAST $XR1 185 
J 0
(1084 -25);
DISPLAY 0.638298 (1084 -25);
PAINT MONO (1084 -25);
FORCEPROP 2 LAST $XR0 201 
J 0
(964 -25);
DISPLAY 0.638298 (964 -25);
PAINT MONO (964 -25);
FORCEPROP 2 LAST PATH I84
J 0
(1125 25);
DISPLAY 1.021277 (1125 25);
DISPLAY INVISIBLE (1125 25);
FORCEPROP 1 LAST COMMENT_BODY TRUE
J 0
(730 -120);
DISPLAY 0.872340 (730 -120);
PAINT GREEN (730 -120);
DISPLAY INVISIBLE (730 -120);
FORCEPROP 1 LAST OFFPAGE TRUE
J 0
(1100 -150);
DISPLAY 0.872340 (1100 -150);
DISPLAY INVISIBLE (1100 -150);
FORCEPROP 2 LAST CDS_LIB standard
J 0
(775 -25);
PAINT MONO (775 -25);
DISPLAY INVISIBLE (775 -25);
FORCEADD Q_RES..1
(-350 -25);
FORCEPROP 1 LAST PART_NUMBER CS00002JB13
J 0
(-400 25);
DISPLAY 0.404255 (-400 25);
DISPLAY INVISIBLE (-400 25);
FORCEPROP 1 LAST MATERIAL EMPTY
J 0
(-100 -25);
DISPLAY 0.510638 (-100 -25);
PAINT RED (-100 -25);
FORCEPROP 1 LAST PACK_TYPE 0402LF
J 0
(-400 50);
DISPLAY 0.404255 (-400 50);
FORCEPROP 1 LAST TOLERANCE 5%
J 0
(-175 -25);
DISPLAY 0.510638 (-175 -25);
FORCEPROP 1 LAST VALUE 0
J 2
(-200 -25);
DISPLAY 0.510638 (-200 -25);
FORCEPROP 1 LAST WATTAGE 1/16W
J 2
(-175 50);
DISPLAY 0.404255 (-175 50);
FORCEPROP 1 LAST $LOCATION R1839
J 0
(-575 -25);
DISPLAY 0.638298 (-575 -25);
FORCEPROP 1 LASTPIN (-450 -25) $PN 1
J 0
(-438 -13);
DISPLAY 0.787234 (-438 -13);
FORCEPROP 1 LASTPIN (-250 -25) $PN 2
J 0
(-288 -13);
DISPLAY 0.787234 (-288 -13);
FORCEPROP 1 LAST PATH I85
J 0
(-400 125);
DISPLAY 0.978723 (-400 125);
PAINT WHITE (-400 125);
DISPLAY INVISIBLE (-400 125);
FORCEPROP 2 LAST CDS_LIB pure_quanta
J 0
(-350 -25);
PAINT MONO (-350 -25);
DISPLAY INVISIBLE (-350 -25);
FORCEPROP 2 LAST CDS_LOCATION R1839
J 0
(-400 175);
DISPLAY 1.021277 (-400 175);
DISPLAY INVISIBLE (-400 175);
FORCEPROP 2 LAST $SEC 1
J 0
(-400 175);
DISPLAY 0.680851 (-400 175);
PAINT MONO (-400 175);
DISPLAY INVISIBLE (-400 175);
FORCEPROP 2 LAST CDS_SEC 1
J 0
(-400 175);
DISPLAY 1.021277 (-400 175);
DISPLAY INVISIBLE (-400 175);
FORCEADD OFFPAGE..2
(775 -925);
FORCEPROP 2 LAST $XR0 185 
J 0
(964 -925);
DISPLAY 0.638298 (964 -925);
PAINT MONO (964 -925);
FORCEPROP 2 LAST PATH I87
J 0
(1125 -875);
DISPLAY 1.021277 (1125 -875);
DISPLAY INVISIBLE (1125 -875);
FORCEPROP 1 LAST COMMENT_BODY TRUE
J 0
(730 -1020);
DISPLAY 0.872340 (730 -1020);
PAINT GREEN (730 -1020);
DISPLAY INVISIBLE (730 -1020);
FORCEPROP 1 LAST OFFPAGE TRUE
J 0
(1100 -1050);
DISPLAY 0.872340 (1100 -1050);
DISPLAY INVISIBLE (1100 -1050);
FORCEPROP 2 LAST CDS_LIB standard
J 0
(775 -925);
PAINT MONO (775 -925);
DISPLAY INVISIBLE (775 -925);
FORCEADD UNIVERSAL_GND..1
(50 -1675);
FORCEPROP 3 LASTPIN (50 -1625) SIG_NAME GND\g
J 0
(60 -1615);
DISPLAY 0.659574 (60 -1615);
PAINT MONO (60 -1615);
DISPLAY INVISIBLE (60 -1615);
FORCEPROP 2 LAST CDS_LIB logical_power
J 0
(50 -1675);
PAINT MONO (50 -1675);
DISPLAY INVISIBLE (50 -1675);
FORCEPROP 1 LAST HDL_POWER GND
J 1
(75 -1750);
DISPLAY 0.872340 (75 -1750);
PAINT GREEN (75 -1750);
DISPLAY INVISIBLE (75 -1750);
FORCEPROP 1 LAST PATH I88
J 0
(125 -1675);
DISPLAY 0.872340 (125 -1675);
PAINT AQUA (125 -1675);
DISPLAY INVISIBLE (125 -1675);
FORCEPROP 2 LAST ROOM IO_SLOT
J 1
(-175 -1600);
DISPLAY 0.744681 (-175 -1600);
DISPLAY INVISIBLE (-175 -1600);
FORCEADD Q_RES..1
(-350 -925);
FORCEPROP 1 LAST PART_NUMBER CS00002JB13
J 0
(-400 -875);
DISPLAY 0.404255 (-400 -875);
DISPLAY INVISIBLE (-400 -875);
FORCEPROP 1 LAST VALUE 0
J 2
(-200 -925);
DISPLAY 0.510638 (-200 -925);
FORCEPROP 1 LAST MATERIAL EMPTY
J 0
(-100 -925);
DISPLAY 0.510638 (-100 -925);
PAINT RED (-100 -925);
FORCEPROP 1 LAST PACK_TYPE 0402LF
J 0
(-400 -850);
DISPLAY 0.404255 (-400 -850);
FORCEPROP 1 LAST TOLERANCE 5%
J 0
(-175 -925);
DISPLAY 0.510638 (-175 -925);
FORCEPROP 1 LAST WATTAGE 1/16W
J 2
(-175 -850);
DISPLAY 0.404255 (-175 -850);
FORCEPROP 1 LAST $LOCATION R1840
J 0
(-575 -925);
DISPLAY 0.638298 (-575 -925);
FORCEPROP 1 LASTPIN (-450 -925) $PN 1
J 0
(-438 -913);
DISPLAY 0.787234 (-438 -913);
FORCEPROP 1 LASTPIN (-250 -925) $PN 2
J 0
(-288 -913);
DISPLAY 0.787234 (-288 -913);
FORCEPROP 1 LAST PATH I89
J 0
(-400 -775);
DISPLAY 0.978723 (-400 -775);
PAINT WHITE (-400 -775);
DISPLAY INVISIBLE (-400 -775);
FORCEPROP 2 LAST CDS_LIB pure_quanta
J 0
(-350 -925);
PAINT MONO (-350 -925);
DISPLAY INVISIBLE (-350 -925);
FORCEPROP 2 LAST CDS_LOCATION R1840
J 0
(-400 -725);
DISPLAY 1.021277 (-400 -725);
DISPLAY INVISIBLE (-400 -725);
FORCEPROP 2 LAST $SEC 1
J 0
(-400 -725);
DISPLAY 0.680851 (-400 -725);
PAINT MONO (-400 -725);
DISPLAY INVISIBLE (-400 -725);
FORCEPROP 2 LAST CDS_SEC 1
J 0
(-400 -725);
DISPLAY 1.021277 (-400 -725);
DISPLAY INVISIBLE (-400 -725);
FORCEADD OFFPAGE..1
(-1375 -1300);
FORCEPROP 2 LAST $XR0 222 
J 0
(-1627 -1300);
DISPLAY 0.638298 (-1627 -1300);
PAINT MONO (-1627 -1300);
FORCEPROP 2 LAST PATH I90
J 0
(-1675 -1250);
DISPLAY 1.021277 (-1675 -1250);
DISPLAY INVISIBLE (-1675 -1250);
FORCEPROP 1 LAST COMMENT_BODY TRUE
J 0
(-1250 -1400);
DISPLAY 0.872340 (-1250 -1400);
PAINT GREEN (-1250 -1400);
DISPLAY INVISIBLE (-1250 -1400);
FORCEPROP 1 LAST OFFPAGE TRUE
J 0
(-1050 -1425);
DISPLAY 0.872340 (-1050 -1425);
DISPLAY INVISIBLE (-1050 -1425);
FORCEPROP 2 LAST CDS_LIB standard
J 0
(-1375 -1300);
PAINT MONO (-1375 -1300);
DISPLAY INVISIBLE (-1375 -1300);
FORCEADD OFFPAGE..2
(6125 -1475);
FORCEPROP 2 LAST $XR0 240 
J 0
(6314 -1475);
DISPLAY 0.638298 (6314 -1475);
PAINT MONO (6314 -1475);
FORCEPROP 2 LAST PATH I92
J 0
(6325 -1425);
DISPLAY 1.021277 (6325 -1425);
DISPLAY INVISIBLE (6325 -1425);
FORCEPROP 1 LAST COMMENT_BODY TRUE
J 0
(6080 -1570);
DISPLAY 1.170213 (6080 -1570);
PAINT GREEN (6080 -1570);
DISPLAY INVISIBLE (6080 -1570);
FORCEPROP 1 LAST OFFPAGE TRUE
J 0
(6450 -1600);
DISPLAY 1.170213 (6450 -1600);
PAINT GREEN (6450 -1600);
DISPLAY INVISIBLE (6450 -1600);
FORCEPROP 2 LAST CDS_LIB standard
J 0
(6125 -1475);
PAINT MONO (6125 -1475);
DISPLAY INVISIBLE (6125 -1475);
FORCEADD OFFPAGE..2
(6125 -750);
FORCEPROP 2 LAST $XR0 240 
J 0
(6314 -750);
DISPLAY 0.638298 (6314 -750);
PAINT MONO (6314 -750);
FORCEPROP 2 LAST PATH I93
J 0
(6325 -700);
DISPLAY 1.021277 (6325 -700);
DISPLAY INVISIBLE (6325 -700);
FORCEPROP 1 LAST COMMENT_BODY TRUE
J 0
(6080 -845);
DISPLAY 1.170213 (6080 -845);
PAINT GREEN (6080 -845);
DISPLAY INVISIBLE (6080 -845);
FORCEPROP 1 LAST OFFPAGE TRUE
J 0
(6450 -875);
DISPLAY 1.170213 (6450 -875);
PAINT GREEN (6450 -875);
DISPLAY INVISIBLE (6450 -875);
FORCEPROP 2 LAST CDS_LIB standard
J 0
(6125 -750);
PAINT MONO (6125 -750);
DISPLAY INVISIBLE (6125 -750);
FORCEADD OFFPAGE..2
(6125 -900);
FORCEPROP 2 LAST $XR0 240 
J 0
(6314 -900);
DISPLAY 0.638298 (6314 -900);
PAINT MONO (6314 -900);
FORCEPROP 2 LAST PATH I95
J 0
(6325 -850);
DISPLAY 1.021277 (6325 -850);
DISPLAY INVISIBLE (6325 -850);
FORCEPROP 1 LAST COMMENT_BODY TRUE
J 0
(6080 -995);
DISPLAY 1.170213 (6080 -995);
PAINT GREEN (6080 -995);
DISPLAY INVISIBLE (6080 -995);
FORCEPROP 1 LAST OFFPAGE TRUE
J 0
(6450 -1025);
DISPLAY 1.170213 (6450 -1025);
PAINT GREEN (6450 -1025);
DISPLAY INVISIBLE (6450 -1025);
FORCEPROP 2 LAST CDS_LIB standard
J 0
(6125 -900);
PAINT MONO (6125 -900);
DISPLAY INVISIBLE (6125 -900);
FORCEADD OFFPAGE..2
(6125 -1175);
FORCEPROP 2 LAST $XR0 240 
J 0
(6314 -1175);
DISPLAY 0.638298 (6314 -1175);
PAINT MONO (6314 -1175);
FORCEPROP 2 LAST PATH I96
J 0
(6325 -1125);
DISPLAY 1.021277 (6325 -1125);
DISPLAY INVISIBLE (6325 -1125);
FORCEPROP 1 LAST COMMENT_BODY TRUE
J 0
(6080 -1270);
DISPLAY 1.170213 (6080 -1270);
PAINT GREEN (6080 -1270);
DISPLAY INVISIBLE (6080 -1270);
FORCEPROP 1 LAST OFFPAGE TRUE
J 0
(6450 -1300);
DISPLAY 1.170213 (6450 -1300);
PAINT GREEN (6450 -1300);
DISPLAY INVISIBLE (6450 -1300);
FORCEPROP 2 LAST CDS_LIB standard
J 0
(6125 -1175);
PAINT MONO (6125 -1175);
DISPLAY INVISIBLE (6125 -1175);
FORCEADD OFFPAGE..2
(6125 -1250);
FORCEPROP 2 LAST $XR0 240 
J 0
(6314 -1250);
DISPLAY 0.638298 (6314 -1250);
PAINT MONO (6314 -1250);
FORCEPROP 2 LAST PATH I97
J 0
(6325 -1200);
DISPLAY 1.021277 (6325 -1200);
DISPLAY INVISIBLE (6325 -1200);
FORCEPROP 1 LAST COMMENT_BODY TRUE
J 0
(6080 -1345);
DISPLAY 1.170213 (6080 -1345);
PAINT GREEN (6080 -1345);
DISPLAY INVISIBLE (6080 -1345);
FORCEPROP 1 LAST OFFPAGE TRUE
J 0
(6450 -1375);
DISPLAY 1.170213 (6450 -1375);
PAINT GREEN (6450 -1375);
DISPLAY INVISIBLE (6450 -1375);
FORCEPROP 2 LAST CDS_LIB standard
J 0
(6125 -1250);
PAINT MONO (6125 -1250);
DISPLAY INVISIBLE (6125 -1250);
FORCEADD OFFPAGE..2
(6125 -1325);
FORCEPROP 2 LAST $XR0 240 
J 0
(6314 -1325);
DISPLAY 0.638298 (6314 -1325);
PAINT MONO (6314 -1325);
FORCEPROP 2 LAST PATH I98
J 0
(6325 -1275);
DISPLAY 1.021277 (6325 -1275);
DISPLAY INVISIBLE (6325 -1275);
FORCEPROP 1 LAST COMMENT_BODY TRUE
J 0
(6080 -1420);
DISPLAY 1.170213 (6080 -1420);
PAINT GREEN (6080 -1420);
DISPLAY INVISIBLE (6080 -1420);
FORCEPROP 1 LAST OFFPAGE TRUE
J 0
(6450 -1450);
DISPLAY 1.170213 (6450 -1450);
PAINT GREEN (6450 -1450);
DISPLAY INVISIBLE (6450 -1450);
FORCEPROP 2 LAST CDS_LIB standard
J 0
(6125 -1325);
PAINT MONO (6125 -1325);
DISPLAY INVISIBLE (6125 -1325);
FORCEADD OFFPAGE..2
(6125 -1400);
FORCEPROP 2 LAST $XR0 240 
J 0
(6314 -1400);
DISPLAY 0.638298 (6314 -1400);
PAINT MONO (6314 -1400);
FORCEPROP 2 LAST PATH I99
J 0
(6325 -1350);
DISPLAY 1.021277 (6325 -1350);
DISPLAY INVISIBLE (6325 -1350);
FORCEPROP 1 LAST COMMENT_BODY TRUE
J 0
(6080 -1495);
DISPLAY 1.170213 (6080 -1495);
PAINT GREEN (6080 -1495);
DISPLAY INVISIBLE (6080 -1495);
FORCEPROP 1 LAST OFFPAGE TRUE
J 0
(6450 -1525);
DISPLAY 1.170213 (6450 -1525);
PAINT GREEN (6450 -1525);
DISPLAY INVISIBLE (6450 -1525);
FORCEPROP 2 LAST CDS_LIB standard
J 0
(6125 -1400);
PAINT MONO (6125 -1400);
DISPLAY INVISIBLE (6125 -1400);
FORCEADD DNS..2
(-325 -925);
PAINT RED (-325 -925);
FORCEPROP 1 LAST COMMENT_BODY TRUE
R 1
J 0
(-250 -1150);
DISPLAY 0.872340 (-250 -1150);
PAINT GREEN (-250 -1150);
DISPLAY INVISIBLE (-250 -1150);
FORCEPROP 2 LAST CDS_LIB mstr_misc
J 0
(-325 -925);
PAINT MONO (-325 -925);
DISPLAY INVISIBLE (-325 -925);
FORCEADD DNS..2
(-325 -25);
PAINT RED (-325 -25);
FORCEPROP 1 LAST COMMENT_BODY TRUE
R 1
J 0
(-250 -250);
DISPLAY 0.872340 (-250 -250);
PAINT GREEN (-250 -250);
DISPLAY INVISIBLE (-250 -250);
FORCEPROP 2 LAST CDS_LIB mstr_misc
J 0
(-325 -25);
PAINT MONO (-325 -25);
DISPLAY INVISIBLE (-325 -25);
FORCEADD QUANTA_TITLE_BLOCK_C..1
(7250 -2375);
FORCEPROP 0 LAST CDS_CON_LAST_MODIFIED Fri Aug 25 14:02:57 2023
J 0
(5365 -2360);
PAINT MONO (5365 -2360);
DISPLAY INVISIBLE (5365 -2360);
FORCEPROP 2 LAST CUSTOM_TXT_CDS <XR_PAGE_TITLE>
J 0
(-640 2875);
DISPLAY 0.638298 (-640 2875);
PAINT PINK (-640 2875);
DISPLAY INVISIBLE (-640 2875);
FORCEPROP 2 LAST CUSTOM_TXT_CDS <CON_LAST_MODIFIED>
J 0
(5375 -2375);
DISPLAY 0.978723 (5375 -2375);
FORCEPROP 2 LAST CUSTOM_TXT_CDS <Q_REV>
J 0
(7066 -2272);
DISPLAY 1.212766 (7066 -2272);
FORCEPROP 2 LAST CUSTOM_TXT_CDS <Q_PROJ>
J 0
(4868 -2273);
DISPLAY 1.212766 (4868 -2273);
FORCEPROP 2 LAST CUSTOM_TXT_CDS <Q_NUMBER>
J 0
(5847 -2272);
DISPLAY 1.212766 (5847 -2272);
FORCEPROP 2 LAST CUSTOM_TXT_CDS <CON_PAGE_NUM> OF <CON_TOTAL_PAGES>
J 0
(6775 -2375);
DISPLAY 0.978723 (6775 -2375);
FORCEPROP 2 LAST CUSTOM_TXT_CDS <NAME_2>
J 0
(4075 -2325);
FORCEPROP 2 LAST CUSTOM_TXT_CDS <NAME_1>
J 0
(4075 -2200);
FORCEPROP 1 LAST Q_TITLE EMMITSBURG - GPIO/SPI (7/10)
J 0
(-2066 -2349);
DISPLAY 1.957447 (-2066 -2349);
PAINT GREEN (-2066 -2349);
FORCEPROP 1 LAST Q_DEPT 
J 1
(3487 -2326);
DISPLAY 1.957447 (3487 -2326);
PAINT GREEN (3487 -2326);
FORCEPROP 2 LAST CDS_XR_PAGE_TITLE CR-185 : @S9S_MB_2U_LIB.S9S_MB_2U(SCH_1):PAGE185
J 0
(-640 2875);
DISPLAY 0.638298 (-640 2875);
PAINT PINK (-640 2875);
DISPLAY INVISIBLE (-640 2875);
FORCEPROP 2 LAST PAGE_BORDER TRUE
J 0
(-640 2875);
DISPLAY 0.638298 (-640 2875);
PAINT PINK (-640 2875);
DISPLAY INVISIBLE (-640 2875);
FORCEPROP 1 LAST CDS_LMAN_SYM_OUTLINE -9475,6775,100,-125
J 0
(7250 -2375);
DISPLAY 0.468085 (7250 -2375);
PAINT GREEN (7250 -2375);
DISPLAY INVISIBLE (7250 -2375);
FORCEPROP 2 LAST CDS_LIB pure_quanta
J 0
(7250 -2375);
PAINT MONO (7250 -2375);
DISPLAY INVISIBLE (7250 -2375);
FORCEPROP 1 LAST COMMENT_BODY TRUE
J 0
(7262 -2388);
DISPLAY 0.978723 (7262 -2388);
PAINT GREEN (7262 -2388);
DISPLAY INVISIBLE (7262 -2388);
WIRE 16 -1 (5125 400)(5125 550);
WIRE 16 -1 (4800 400)(5125 400);
WIRE 16 -1 (5125 250)(5125 400);
WIRE 16 -1 (4075 350)(4075 725);
WIRE 16 -1 (3725 350)(4075 350);
WIRE 16 -1 (4075 350)(4600 350);
FORCEPROP 2 LAST SIG_NAME P3V_BAT_R
J 0
(4140 360);
DISPLAY 0.680851 (4140 360);
PAINT WHITE (4140 360);
FORCEPROP 2 LASTPROP $XR0 240 
J 0
(3870 360);
DISPLAY 0.638298 (3870 360);
PAINT MONO (3870 360);
WIRE 16 -1 (3625 3725)(3625 3650);
WIRE 16 -1 (-1400 1250)(-1400 1175);
WIRE 16 -1 (4500 850)(4500 450);
WIRE 16 -1 (50 -600)(50 -725);
WIRE 16 -1 (50 -1500)(50 -1625);
WIRE 16 -1 (5125 50)(5125 -25);
WIRE 16 -1 (-1400 575)(-1400 475);
WIRE 16 -1 (2400 200)(2400 350);
WIRE 16 -1 (-1125 -725)(-1125 -825);
WIRE 16 -1 (-1125 -1625)(-1125 -1725);
WIRE 16 2175 (-1175 -1350)(-800 -1350);
WIRE 16 2175 (-800 -1350)(-800 -1850);
WIRE 16 2175 (-1175 -1350)(-1175 -1850);
WIRE 16 2175 (-1175 -1850)(-800 -1850);
WIRE 16 -1 (-1125 -1300)(-1325 -1300);
FORCEPROP 0 LAST CDS_PHYS_NET_NAME FM_PCH_CRASHLOG_TRIG_R_N
J 0
(-1160 -1258);
PAINT MONO (-1160 -1258);
DISPLAY INVISIBLE (-1160 -1258);
FORCEPROP 2 LAST SIG_NAME RST_PFR_OVR_SRTC
J 0
(-1235 -1290);
DISPLAY 0.680851 (-1235 -1290);
PAINT WHITE (-1235 -1290);
WIRE 16 -1 (-1125 -1425)(-1125 -1300);
WIRE 16 -1 (-625 -1300)(-1125 -1300);
WIRE 16 -1 (-150 -1300)(-625 -1300);
WIRE 16 -1 (-625 -1300)(-625 -925);
WIRE 16 -1 (-625 -925)(-450 -925);
WIRE 16 2175 (-275 -1050)(600 -1050);
WIRE 16 2175 (600 -1050)(600 -1550);
WIRE 16 2175 (-275 -1050)(-275 -1550);
WIRE 16 2175 (-275 -1550)(600 -1550);
WIRE 16 2175 (-1200 -450)(-825 -450);
WIRE 16 2175 (-825 -450)(-825 -950);
WIRE 16 2175 (-1200 -450)(-1200 -950);
WIRE 16 2175 (-1200 -950)(-825 -950);
WIRE 16 2175 (-250 -150)(625 -150);
WIRE 16 2175 (625 -150)(625 -650);
WIRE 16 2175 (-250 -150)(-250 -650);
WIRE 16 2175 (-250 -650)(625 -650);
WIRE 16 -1 (2400 350)(2525 350);
WIRE 16 -1 (4500 450)(4600 450);
WIRE 16 -1 (-1125 -525)(-1125 -400);
WIRE 16 -1 (-1125 -400)(-1325 -400);
FORCEPROP 0 LAST CDS_PHYS_NET_NAME FM_PCH_CRASHLOG_TRIG_R_N
J 0
(-1160 -358);
PAINT MONO (-1160 -358);
DISPLAY INVISIBLE (-1160 -358);
FORCEPROP 2 LAST SIG_NAME RST_PFR_OVR_RTC
J 0
(-1235 -390);
DISPLAY 0.680851 (-1235 -390);
PAINT WHITE (-1235 -390);
WIRE 16 -1 (-625 -400)(-1125 -400);
WIRE 16 -1 (-150 -400)(-625 -400);
WIRE 16 -1 (-625 -400)(-625 -25);
WIRE 16 -1 (-625 -25)(-450 -25);
WIRE 16 -1 (50 -1100)(50 -925);
WIRE 16 -1 (725 -925)(50 -925);
FORCEPROP 2 LAST SIG_NAME RST_SRTCRST_N
J 0
(225 -915);
DISPLAY 0.659574 (225 -915);
PAINT WHITE (225 -915);
WIRE 16 -1 (-250 -925)(50 -925);
WIRE 16 -1 (2575 -1400)(4100 -1400);
FORCEPROP 2 LAST SIG_NAME SPI_PCH_IO3
J 0
(2690 -1390);
DISPLAY 0.851064 (2690 -1390);
PAINT WHITE (2690 -1390);
WIRE 16 -1 (2575 -1475)(4100 -1475);
FORCEPROP 2 LAST SIG_NAME SPI_PCH_CLK
J 0
(2690 -1465);
DISPLAY 0.851064 (2690 -1465);
PAINT WHITE (2690 -1465);
WIRE 16 2175 (3950 -1100)(4575 -1100);
WIRE 16 2175 (4575 -1100)(4575 -1425);
WIRE 16 2175 (3950 -1100)(3950 -1425);
WIRE 16 2175 (3950 -1425)(4575 -1425);
WIRE 16 -1 (2575 -1325)(4100 -1325);
FORCEPROP 2 LAST SIG_NAME SPI_PCH_IO2
J 0
(2690 -1315);
DISPLAY 0.851064 (2690 -1315);
PAINT WHITE (2690 -1315);
WIRE 16 -1 (6075 -1325)(4300 -1325);
FORCEPROP 2 LAST SIG_NAME SPI_SYS_WP_IO2
J 0
(4890 -1315);
DISPLAY 0.851064 (4890 -1315);
PAINT WHITE (4890 -1315);
WIRE 16 -1 (4300 -1400)(6075 -1400);
FORCEPROP 2 LAST SIG_NAME SPI_SYS_HOLD_IO3
J 0
(4890 -1390);
DISPLAY 0.851064 (4890 -1390);
PAINT WHITE (4890 -1390);
WIRE 16 -1 (6075 -1250)(4300 -1250);
FORCEPROP 2 LAST SIG_NAME SPI_SYS_MISO
J 0
(4890 -1240);
DISPLAY 0.851064 (4890 -1240);
PAINT WHITE (4890 -1240);
WIRE 16 -1 (6075 -1175)(4300 -1175);
FORCEPROP 2 LAST SIG_NAME SPI_SYS_MOSI
J 0
(4890 -1165);
DISPLAY 0.851064 (4890 -1165);
PAINT WHITE (4890 -1165);
WIRE 16 -1 (4300 -1475)(6075 -1475);
FORCEPROP 2 LAST SIG_NAME SPI_SYS_CLK
J 0
(4890 -1465);
DISPLAY 0.851064 (4890 -1465);
PAINT WHITE (4890 -1465);
WIRE 16 -1 (2575 -1250)(4100 -1250);
FORCEPROP 2 LAST SIG_NAME SPI_PCH_IO1
J 0
(2690 -1240);
DISPLAY 0.851064 (2690 -1240);
PAINT WHITE (2690 -1240);
WIRE 16 -1 (2575 -1175)(4100 -1175);
FORCEPROP 2 LAST SIG_NAME SPI_PCH_IO0
J 0
(2690 -1165);
DISPLAY 0.851064 (2690 -1165);
PAINT WHITE (2690 -1165);
WIRE 16 -1 (4125 -750)(2575 -750);
FORCEPROP 2 LAST SIG_NAME SPI_PCH_CS0_R_N
J 0
(2690 -740);
DISPLAY 0.851064 (2690 -740);
PAINT WHITE (2690 -740);
WIRE 16 -1 (3525 350)(2925 350);
FORCEPROP 2 LAST SIG_NAME P3V_BAT
J 0
(3065 360);
DISPLAY 0.680851 (3065 360);
PAINT WHITE (3065 360);
WIRE 16 -1 (50 -200)(50 -25);
WIRE 16 -1 (725 -25)(50 -25);
FORCEPROP 2 LAST SIG_NAME RST_RTCRST_N
J 0
(225 -15);
DISPLAY 0.659574 (225 -15);
PAINT WHITE (225 -15);
WIRE 16 -1 (-250 -25)(50 -25);
WIRE 16 -1 (4200 2250)(2750 2250);
FORCEPROP 2 LAST SIG_NAME SPI_PCH_IO3
J 0
(2950 2260);
DISPLAY 0.659574 (2950 2260);
PAINT WHITE (2950 2260);
WIRE 16 -1 (4200 2350)(2750 2350);
FORCEPROP 2 LAST SIG_NAME SPI_PCH_IO1
J 0
(2950 2360);
DISPLAY 0.659574 (2950 2360);
PAINT WHITE (2950 2360);
WIRE 16 -1 (2750 2600)(4200 2600);
FORCEPROP 0 LAST CDS_PHYS_NET_NAME SPI_PCH_TPM_CS_N
J 0
(2900 2610);
PAINT MONO (2900 2610);
DISPLAY INVISIBLE (2900 2610);
FORCEPROP 2 LAST SIG_NAME FM_XTAL_INPUT_FREQUENCY_0_MGPIO_TEST4
J 0
(2950 2610);
DISPLAY 0.659574 (2950 2610);
PAINT WHITE (2950 2610);
WIRE 16 -1 (2750 2650)(4200 2650);
FORCEPROP 0 LAST CDS_PHYS_NET_NAME SPI_PCH_TPM_CS_N
J 0
(2900 2660);
PAINT MONO (2900 2660);
DISPLAY INVISIBLE (2900 2660);
FORCEPROP 2 LAST SIG_NAME FM_PCH_SPKR
J 0
(2940 2660);
DISPLAY 0.659574 (2940 2660);
PAINT WHITE (2940 2660);
WIRE 16 -1 (2750 2700)(4200 2700);
FORCEPROP 0 LAST CDS_PHYS_NET_NAME SPI_PCH_TPM_CS_N
J 0
(2900 2710);
PAINT MONO (2900 2710);
DISPLAY INVISIBLE (2900 2710);
FORCEPROP 2 LAST SIG_NAME FM_XTAL_INPUT_FREQUENCY_1_MGPIO_TEST5
J 0
(2950 2710);
DISPLAY 0.659574 (2950 2710);
PAINT WHITE (2950 2710);
WIRE 16 -1 (2750 2750)(4200 2750);
FORCEPROP 0 LAST CDS_PHYS_NET_NAME SPI_PCH_TPM_CS_N
J 0
(2900 2760);
PAINT MONO (2900 2760);
DISPLAY INVISIBLE (2900 2760);
FORCEPROP 2 LAST SIG_NAME FM_ADR_MODE0
J 0
(2950 2760);
DISPLAY 0.659574 (2950 2760);
PAINT WHITE (2950 2760);
WIRE 16 -1 (2750 2800)(4200 2800);
FORCEPROP 0 LAST CDS_PHYS_NET_NAME SPI_PCH_TPM_CS_N
J 0
(2900 2810);
PAINT MONO (2900 2810);
DISPLAY INVISIBLE (2900 2810);
FORCEPROP 2 LAST SIG_NAME FM_SPI_3V3_1V8_VOLTAGE
J 0
(2950 2810);
DISPLAY 0.659574 (2950 2810);
PAINT WHITE (2950 2810);
WIRE 16 -1 (2750 2850)(4200 2850);
FORCEPROP 0 LAST CDS_PHYS_NET_NAME SPI_PCH_TPM_CS_N
J 0
(2900 2860);
PAINT MONO (2900 2860);
DISPLAY INVISIBLE (2900 2860);
FORCEPROP 2 LAST SIG_NAME FM_PCH_CONSENT_STRAP_N
J 0
(2950 2860);
DISPLAY 0.659574 (2950 2860);
PAINT WHITE (2950 2860);
WIRE 16 -1 (4200 2550)(2750 2550);
FORCEPROP 0 LAST CDS_PHYS_NET_NAME SPI_PCH_TPM_CS_N
J 0
(2900 2560);
PAINT MONO (2900 2560);
DISPLAY INVISIBLE (2900 2560);
FORCEPROP 2 LAST SIG_NAME SPI_PCH_CLK
J 0
(2950 2560);
DISPLAY 0.659574 (2950 2560);
PAINT WHITE (2950 2560);
WIRE 16 -1 (2750 2500)(4200 2500);
FORCEPROP 0 LAST CDS_PHYS_NET_NAME TP_SPI_PCH_CS1_N
J 0
(2900 2549);
PAINT MONO (2900 2549);
DISPLAY INVISIBLE (2900 2549);
FORCEPROP 2 LAST SIG_NAME TP_SPI_PCH_CS1_R_N
J 0
(2950 2510);
DISPLAY 0.659574 (2950 2510);
PAINT WHITE (2950 2510);
WIRE 16 -1 (4200 2400)(2750 2400);
FORCEPROP 0 LAST CDS_PHYS_NET_NAME SPI_PCH_TPM_CS_N
J 0
(2900 2410);
PAINT MONO (2900 2410);
DISPLAY INVISIBLE (2900 2410);
FORCEPROP 2 LAST SIG_NAME SPI_PCH_TPM_CS_N
J 0
(2950 2410);
DISPLAY 0.659574 (2950 2410);
PAINT WHITE (2950 2410);
WIRE 16 -1 (2750 2100)(4200 2100);
FORCEPROP 2 LAST SIG_NAME RST_RTCRST_N
J 0
(2950 2110);
DISPLAY 0.659574 (2950 2110);
PAINT WHITE (2950 2110);
WIRE 16 -1 (2750 2300)(4200 2300);
FORCEPROP 2 LAST SIG_NAME SPI_PCH_IO0
J 0
(2950 2310);
DISPLAY 0.659574 (2950 2310);
PAINT WHITE (2950 2310);
WIRE 16 -1 (2750 2450)(4200 2450);
FORCEPROP 0 LAST CDS_PHYS_NET_NAME TP_SPI_PCH_CS1_N
J 0
(2900 2499);
PAINT MONO (2900 2499);
DISPLAY INVISIBLE (2900 2499);
FORCEPROP 2 LAST SIG_NAME SPI_PCH_CS0_R_N
J 0
(2950 2460);
DISPLAY 0.659574 (2950 2460);
PAINT WHITE (2950 2460);
WIRE 16 -1 (4200 2200)(2750 2200);
FORCEPROP 2 LAST SIG_NAME SPI_PCH_IO2
J 0
(2950 2210);
DISPLAY 0.659574 (2950 2210);
PAINT WHITE (2950 2210);
WIRE 16 -1 (4200 2050)(2750 2050);
FORCEPROP 2 LAST SIG_NAME RST_SRTCRST_N
J 0
(2950 2060);
DISPLAY 0.659574 (2950 2060);
PAINT WHITE (2950 2060);
WIRE 16 -1 (2575 -900)(4125 -900);
FORCEPROP 2 LAST SIG_NAME SPI_PCH_TPM_CS_N
J 0
(2690 -890);
DISPLAY 0.851064 (2690 -890);
PAINT WHITE (2690 -890);
WIRE 16 -1 (4125 -500)(2575 -500);
FORCEPROP 0 LAST CDS_PHYS_NET_NAME FM_PCH_CRASHLOG_TRIG_R_N
J 0
(2740 -458);
PAINT MONO (2740 -458);
DISPLAY INVISIBLE (2740 -458);
FORCEPROP 2 LAST SIG_NAME FM_EUP_LOT6_N
J 0
(2690 -490);
DISPLAY 0.851064 (2690 -490);
PAINT WHITE (2690 -490);
WIRE 16 -1 (4325 -900)(6075 -900);
FORCEPROP 2 LAST SIG_NAME SPI_TPM_CS_N
J 0
(4890 -890);
DISPLAY 0.851064 (4890 -890);
PAINT WHITE (4890 -890);
WIRE 16 -1 (4325 -750)(6075 -750);
FORCEPROP 2 LAST SIG_NAME SPI_SYS_CS0_N
J 0
(4890 -740);
DISPLAY 0.851064 (4890 -740);
PAINT WHITE (4890 -740);
WIRE 16 -1 (4325 -500)(6075 -500);
FORCEPROP 0 LAST CDS_PHYS_NET_NAME FM_PCH_CRASHLOG_TRIG_N
J 0
(5690 -458);
PAINT MONO (5690 -458);
DISPLAY INVISIBLE (5690 -458);
FORCEPROP 2 LAST SIG_NAME FM_SUSACK_N
J 0
(4890 -490);
DISPLAY 0.851064 (4890 -490);
PAINT WHITE (4890 -490);
WIRE 16 -1 (-1575 3300)(-500 3300);
FORCEPROP 0 LAST CDS_PHYS_NET_NAME FM_PCH_SLP_S4_N
J 0
(-1550 3342);
PAINT MONO (-1550 3342);
DISPLAY INVISIBLE (-1550 3342);
FORCEPROP 0 LAST SIG_NAME TP_PCH_GPP_N_1
J 0
(-1475 3310);
DISPLAY 0.680851 (-1475 3310);
PAINT WHITE (-1475 3310);
WIRE 16 -1 (-1575 3200)(-500 3200);
FORCEPROP 0 LAST CDS_PHYS_NET_NAME FM_PCH_SLP_S4_N
J 0
(-1550 3242);
PAINT MONO (-1550 3242);
DISPLAY INVISIBLE (-1550 3242);
FORCEPROP 0 LAST SIG_NAME TP_PCH_GPP_N_4
J 0
(-1475 3210);
DISPLAY 0.680851 (-1475 3210);
PAINT WHITE (-1475 3210);
WIRE 16 -1 (2750 3250)(3725 3250);
FORCEPROP 0 LAST CDS_PHYS_NET_NAME SPI_PCH_TPM_CS_N
J 0
(2900 3260);
PAINT MONO (2900 3260);
DISPLAY INVISIBLE (2900 3260);
FORCEPROP 2 LAST SIG_NAME TP_PCH_CGC_DUT_DETECTED
J 0
(2950 3260);
DISPLAY 0.659574 (2950 3260);
PAINT WHITE (2950 3260);
WIRE 16 -1 (2750 3300)(3625 3300);
FORCEPROP 0 LAST CDS_PHYS_NET_NAME SPI_PCH_TPM_CS_N
J 0
(2900 3310);
PAINT MONO (2900 3310);
DISPLAY INVISIBLE (2900 3310);
FORCEPROP 2 LAST SIG_NAME FM_PCH_PRSNT_N
J 0
(2950 3310);
DISPLAY 0.659574 (2950 3310);
PAINT WHITE (2950 3310);
WIRE 16 -1 (3625 3300)(4200 3300);
WIRE 16 -1 (3625 3450)(3625 3300);
WIRE 16 -1 (-1400 975)(-1400 850);
WIRE 16 -1 (-550 850)(-1400 850);
FORCEPROP 0 LAST SIG_NAME RST_SRTCRST_N
J 2
(-635 860);
DISPLAY 0.829787 (-635 860);
PAINT WHITE (-635 860);
WIRE 16 -1 (-1400 775)(-1400 850);
WIRE 16 -1 (2750 3150)(4200 3150);
FORCEPROP 0 LAST CDS_PHYS_NET_NAME SPI_PCH_TPM_CS_N
J 0
(2900 3160);
PAINT MONO (2900 3160);
DISPLAY INVISIBLE (2900 3160);
FORCEPROP 2 LAST SIG_NAME FM_ESPI_CS_SWIZZLE
J 0
(2950 3160);
DISPLAY 0.659574 (2950 3160);
PAINT WHITE (2950 3160);
WIRE 16 -1 (2750 3100)(4200 3100);
FORCEPROP 0 LAST CDS_PHYS_NET_NAME SPI_PCH_TPM_CS_N
J 0
(2900 3110);
PAINT MONO (2900 3110);
DISPLAY INVISIBLE (2900 3110);
FORCEPROP 2 LAST SIG_NAME FM_JTAG_ODT_DISABLE
J 0
(2950 3110);
DISPLAY 0.659574 (2950 3110);
PAINT WHITE (2950 3110);
WIRE 16 -1 (2750 3050)(4200 3050);
FORCEPROP 0 LAST CDS_PHYS_NET_NAME SPI_PCH_TPM_CS_N
J 0
(2900 3060);
PAINT MONO (2900 3060);
DISPLAY INVISIBLE (2900 3060);
FORCEPROP 2 LAST SIG_NAME IRQ_SMI_ACTIVE_N
J 0
(2950 3060);
DISPLAY 0.659574 (2950 3060);
PAINT WHITE (2950 3060);
WIRE 16 -1 (2750 3000)(4200 3000);
FORCEPROP 0 LAST CDS_PHYS_NET_NAME SPI_PCH_TPM_CS_N
J 0
(2900 3010);
PAINT MONO (2900 3010);
DISPLAY INVISIBLE (2900 3010);
FORCEPROP 2 LAST SIG_NAME IRQ_PCH_CPU_NMI_EVENT_R_N
J 0
(2950 3010);
DISPLAY 0.659574 (2950 3010);
PAINT WHITE (2950 3010);
WIRE 16 -1 (2750 2950)(4200 2950);
FORCEPROP 0 LAST CDS_PHYS_NET_NAME SPI_PCH_TPM_CS_N
J 0
(2900 2960);
PAINT MONO (2900 2960);
DISPLAY INVISIBLE (2900 2960);
FORCEPROP 2 LAST SIG_NAME FM_SUSACK_N
J 0
(2950 2960);
DISPLAY 0.659574 (2950 2960);
PAINT WHITE (2950 2960);
WIRE 16 -1 (2750 2900)(4200 2900);
FORCEPROP 0 LAST CDS_PHYS_NET_NAME SPI_PCH_TPM_CS_N
J 0
(2900 2910);
PAINT MONO (2900 2910);
DISPLAY INVISIBLE (2900 2910);
FORCEPROP 2 LAST SIG_NAME FM_EUP_LOT6_N
J 0
(2950 2910);
DISPLAY 0.659574 (2950 2910);
PAINT WHITE (2950 2910);
DOT 1 (50 -925);
DOT 1 (4075 350);
DOT 1 (5125 400);
DOT 1 (-1400 850);
DOT 1 (-625 -1300);
DOT 1 (3625 3300);
DOT 1 (50 -25);
DOT 1 (-625 -400);
DOT 1 (-1125 -400);
DOT 1 (-1125 -1300);
FORCENOTE
BATTERY
(3125 1000) 0;
DISPLAY LEFT (3125 1000);
DISPLAY 2.000000 (3125 1000);
PAINT WHITE (3125 1000);
FORCENOTE
20211130 CHANGE TO 0 OHM
(3750 -1075) 0;
DISPLAY LEFT (3750 -1075);
DISPLAY 1.021277 (3750 -1075);
PAINT PINK (3750 -1075);
FORCENOTE
ADD 22 OHM ON SCM BD
(3825 -1600) 0;
DISPLAY LEFT (3825 -1600);
DISPLAY 1.021277 (3825 -1600);
PAINT PINK (3825 -1600);
FORCENOTE
20220725 POP Q34
(650 -200) 0;
DISPLAY LEFT (650 -200);
DISPLAY 1.021277 (650 -200);
PAINT PINK (650 -200);
FORCENOTE
20220729 POP Q35
(625 -1100) 0;
DISPLAY LEFT (625 -1100);
DISPLAY 1.021277 (625 -1100);
PAINT PINK (625 -1100);
FORCENOTE
20220729 POP R4712,R4713
(-1825 -1125) 0;
DISPLAY LEFT (-1825 -1125);
DISPLAY 1.021277 (-1825 -1125);
PAINT PINK (-1825 -1125);
QUIT
